FILE_TYPE = MACRO_DRAWING;
SET COLOR_WIRE YELLOW;
SET COLOR_PROP ORANGE;
SET COLOR_DOT WHITE;
SET COLOR_ARC YELLOW;
SET COLOR_BODY GREEN;
SET COLOR_NOTE PURPLE;
SET PROP_DISPLAY VALUE;
SET PAGE_NUMBER P67;
FORCEADD Q_CAP..1
(-10425 5850);
FORCEPROP 1 LAST LOCATION C2154
J 0
(-10375 5950);
DISPLAY 0.489362 (-10375 5950);
PAINT SKYBLUE (-10375 5950);
FORCEPROP 2 LAST $SEC 1
J 0
(-10375 6050);
DISPLAY 0.680851 (-10375 6050);
PAINT MONO (-10375 6050);
DISPLAY INVISIBLE (-10375 6050);
FORCEPROP 2 LAST CDS_SEC 1
J 0
(-10375 6050);
DISPLAY 1.021277 (-10375 6050);
DISPLAY INVISIBLE (-10375 6050);
FORCEPROP 1 LASTPIN (-10425 5950) $PN 1
J 0
(-10415 5930);
DISPLAY 0.489362 (-10415 5930);
FORCEPROP 1 LASTPIN (-10425 5750) $PN 2
J 0
(-10415 5730);
DISPLAY 0.489362 (-10415 5730);
FORCEPROP 1 LAST MATERIAL X6S
J 0
(-10375 5750);
DISPLAY 0.489362 (-10375 5750);
PAINT SKYBLUE (-10375 5750);
FORCEPROP 1 LAST TOLERANCE 20%
J 0
(-10375 5800);
DISPLAY 0.489362 (-10375 5800);
PAINT SKYBLUE (-10375 5800);
FORCEPROP 1 LAST VALUE 22UF
J 0
(-10375 5900);
DISPLAY 0.489362 (-10375 5900);
PAINT SKYBLUE (-10375 5900);
FORCEPROP 1 LAST VOLTAGE 4V
J 0
(-10375 5850);
DISPLAY 0.489362 (-10375 5850);
PAINT SKYBLUE (-10375 5850);
FORCEPROP 1 LAST PACK_TYPE C0402
J 0
(-10375 5650);
DISPLAY 0.489362 (-10375 5650);
PAINT SKYBLUE (-10375 5650);
FORCEPROP 2 LAST CDS_LIB pure_quanta
J 0
(-10425 5850);
PAINT MONO (-10425 5850);
DISPLAY INVISIBLE (-10425 5850);
FORCEPROP 1 LAST PATH I100
J 0
(-10375 6000);
DISPLAY 0.978723 (-10375 6000);
PAINT WHITE (-10375 6000);
DISPLAY INVISIBLE (-10375 6000);
FORCEPROP 1 LAST PART_NUMBER CH622KMEB02
J 0
(-10375 5700);
DISPLAY 0.489362 (-10375 5700);
PAINT SKYBLUE (-10375 5700);
DISPLAY INVISIBLE (-10375 5700);
FORCEADD Q_CAP..1
(-9975 5050);
FORCEPROP 1 LAST LOCATION C3894
J 0
(-9925 5150);
DISPLAY 0.489362 (-9925 5150);
PAINT SKYBLUE (-9925 5150);
FORCEPROP 2 LAST $SEC 1
J 0
(-9925 5250);
DISPLAY 0.680851 (-9925 5250);
PAINT MONO (-9925 5250);
DISPLAY INVISIBLE (-9925 5250);
FORCEPROP 2 LAST CDS_SEC 1
J 0
(-9925 5250);
DISPLAY 1.021277 (-9925 5250);
DISPLAY INVISIBLE (-9925 5250);
FORCEPROP 1 LASTPIN (-9975 5150) $PN 1
J 0
(-9965 5130);
DISPLAY 0.489362 (-9965 5130);
FORCEPROP 1 LASTPIN (-9975 4950) $PN 2
J 0
(-9965 4930);
DISPLAY 0.489362 (-9965 4930);
FORCEPROP 1 LAST MATERIAL X6S
J 0
(-9925 4950);
DISPLAY 0.489362 (-9925 4950);
PAINT SKYBLUE (-9925 4950);
FORCEPROP 1 LAST TOLERANCE 20%
J 0
(-9925 5000);
DISPLAY 0.489362 (-9925 5000);
PAINT SKYBLUE (-9925 5000);
FORCEPROP 1 LAST VALUE 22UF
J 0
(-9925 5100);
DISPLAY 0.489362 (-9925 5100);
PAINT SKYBLUE (-9925 5100);
FORCEPROP 1 LAST VOLTAGE 4V
J 0
(-9925 5050);
DISPLAY 0.489362 (-9925 5050);
PAINT SKYBLUE (-9925 5050);
FORCEPROP 1 LAST PACK_TYPE C0402
J 0
(-9925 4850);
DISPLAY 0.489362 (-9925 4850);
PAINT SKYBLUE (-9925 4850);
FORCEPROP 2 LAST CDS_LIB pure_quanta
J 0
(-9975 5050);
PAINT MONO (-9975 5050);
DISPLAY INVISIBLE (-9975 5050);
FORCEPROP 1 LAST PATH I101
J 0
(-9925 5200);
DISPLAY 0.978723 (-9925 5200);
PAINT WHITE (-9925 5200);
DISPLAY INVISIBLE (-9925 5200);
FORCEPROP 1 LAST PART_NUMBER CH622KMEB02
J 0
(-9925 4900);
DISPLAY 0.489362 (-9925 4900);
PAINT SKYBLUE (-9925 4900);
DISPLAY INVISIBLE (-9925 4900);
FORCEADD Q_CAP..1
(-9525 5050);
FORCEPROP 1 LAST LOCATION C3895
J 0
(-9475 5150);
DISPLAY 0.489362 (-9475 5150);
PAINT SKYBLUE (-9475 5150);
FORCEPROP 2 LAST $SEC 1
J 0
(-9475 5250);
DISPLAY 0.680851 (-9475 5250);
PAINT MONO (-9475 5250);
DISPLAY INVISIBLE (-9475 5250);
FORCEPROP 2 LAST CDS_SEC 1
J 0
(-9475 5250);
DISPLAY 1.021277 (-9475 5250);
DISPLAY INVISIBLE (-9475 5250);
FORCEPROP 1 LASTPIN (-9525 5150) $PN 1
J 0
(-9515 5130);
DISPLAY 0.489362 (-9515 5130);
FORCEPROP 1 LASTPIN (-9525 4950) $PN 2
J 0
(-9515 4930);
DISPLAY 0.489362 (-9515 4930);
FORCEPROP 1 LAST MATERIAL X6S
J 0
(-9475 4950);
DISPLAY 0.489362 (-9475 4950);
PAINT SKYBLUE (-9475 4950);
FORCEPROP 1 LAST TOLERANCE 20%
J 0
(-9475 5000);
DISPLAY 0.489362 (-9475 5000);
PAINT SKYBLUE (-9475 5000);
FORCEPROP 1 LAST VALUE 22UF
J 0
(-9475 5100);
DISPLAY 0.489362 (-9475 5100);
PAINT SKYBLUE (-9475 5100);
FORCEPROP 1 LAST VOLTAGE 4V
J 0
(-9475 5050);
DISPLAY 0.489362 (-9475 5050);
PAINT SKYBLUE (-9475 5050);
FORCEPROP 1 LAST PACK_TYPE C0402
J 0
(-9475 4850);
DISPLAY 0.489362 (-9475 4850);
PAINT SKYBLUE (-9475 4850);
FORCEPROP 2 LAST CDS_LIB pure_quanta
J 0
(-9525 5050);
PAINT MONO (-9525 5050);
DISPLAY INVISIBLE (-9525 5050);
FORCEPROP 1 LAST PATH I102
J 0
(-9475 5200);
DISPLAY 0.978723 (-9475 5200);
PAINT WHITE (-9475 5200);
DISPLAY INVISIBLE (-9475 5200);
FORCEPROP 1 LAST PART_NUMBER CH622KMEB02
J 0
(-9475 4900);
DISPLAY 0.489362 (-9475 4900);
PAINT SKYBLUE (-9475 4900);
DISPLAY INVISIBLE (-9475 4900);
FORCEADD Q_CAP..1
(-9975 5850);
FORCEPROP 1 LAST LOCATION C2157
J 0
(-9925 5950);
DISPLAY 0.489362 (-9925 5950);
PAINT SKYBLUE (-9925 5950);
FORCEPROP 2 LAST $SEC 1
J 0
(-9925 6050);
DISPLAY 0.680851 (-9925 6050);
PAINT MONO (-9925 6050);
DISPLAY INVISIBLE (-9925 6050);
FORCEPROP 2 LAST CDS_SEC 1
J 0
(-9925 6050);
DISPLAY 1.021277 (-9925 6050);
DISPLAY INVISIBLE (-9925 6050);
FORCEPROP 1 LASTPIN (-9975 5950) $PN 1
J 0
(-9965 5930);
DISPLAY 0.489362 (-9965 5930);
FORCEPROP 1 LASTPIN (-9975 5750) $PN 2
J 0
(-9965 5730);
DISPLAY 0.489362 (-9965 5730);
FORCEPROP 1 LAST MATERIAL X6S
J 0
(-9925 5750);
DISPLAY 0.489362 (-9925 5750);
PAINT SKYBLUE (-9925 5750);
FORCEPROP 1 LAST TOLERANCE 20%
J 0
(-9925 5800);
DISPLAY 0.489362 (-9925 5800);
PAINT SKYBLUE (-9925 5800);
FORCEPROP 1 LAST VALUE 22UF
J 0
(-9925 5900);
DISPLAY 0.489362 (-9925 5900);
PAINT SKYBLUE (-9925 5900);
FORCEPROP 1 LAST VOLTAGE 4V
J 0
(-9925 5850);
DISPLAY 0.489362 (-9925 5850);
PAINT SKYBLUE (-9925 5850);
FORCEPROP 1 LAST PACK_TYPE C0402
J 0
(-9925 5650);
DISPLAY 0.489362 (-9925 5650);
PAINT SKYBLUE (-9925 5650);
FORCEPROP 2 LAST CDS_LIB pure_quanta
J 0
(-9975 5850);
PAINT MONO (-9975 5850);
DISPLAY INVISIBLE (-9975 5850);
FORCEPROP 1 LAST PATH I103
J 0
(-9925 6000);
DISPLAY 0.978723 (-9925 6000);
PAINT WHITE (-9925 6000);
DISPLAY INVISIBLE (-9925 6000);
FORCEPROP 1 LAST PART_NUMBER CH622KMEB02
J 0
(-9925 5700);
DISPLAY 0.489362 (-9925 5700);
PAINT SKYBLUE (-9925 5700);
DISPLAY INVISIBLE (-9925 5700);
FORCEADD Q_CAP..1
(-9525 5850);
FORCEPROP 1 LAST LOCATION C2159
J 0
(-9475 5950);
DISPLAY 0.489362 (-9475 5950);
PAINT SKYBLUE (-9475 5950);
FORCEPROP 2 LAST $SEC 1
J 0
(-9475 6050);
DISPLAY 0.680851 (-9475 6050);
PAINT MONO (-9475 6050);
DISPLAY INVISIBLE (-9475 6050);
FORCEPROP 2 LAST CDS_SEC 1
J 0
(-9475 6050);
DISPLAY 1.021277 (-9475 6050);
DISPLAY INVISIBLE (-9475 6050);
FORCEPROP 1 LASTPIN (-9525 5950) $PN 1
J 0
(-9515 5930);
DISPLAY 0.489362 (-9515 5930);
FORCEPROP 1 LASTPIN (-9525 5750) $PN 2
J 0
(-9515 5730);
DISPLAY 0.489362 (-9515 5730);
FORCEPROP 1 LAST MATERIAL X6S
J 0
(-9475 5750);
DISPLAY 0.489362 (-9475 5750);
PAINT SKYBLUE (-9475 5750);
FORCEPROP 1 LAST TOLERANCE 20%
J 0
(-9475 5800);
DISPLAY 0.489362 (-9475 5800);
PAINT SKYBLUE (-9475 5800);
FORCEPROP 1 LAST VALUE 22UF
J 0
(-9475 5900);
DISPLAY 0.489362 (-9475 5900);
PAINT SKYBLUE (-9475 5900);
FORCEPROP 1 LAST VOLTAGE 4V
J 0
(-9475 5850);
DISPLAY 0.489362 (-9475 5850);
PAINT SKYBLUE (-9475 5850);
FORCEPROP 1 LAST PACK_TYPE C0402
J 0
(-9475 5650);
DISPLAY 0.489362 (-9475 5650);
PAINT SKYBLUE (-9475 5650);
FORCEPROP 2 LAST CDS_LIB pure_quanta
J 0
(-9525 5850);
PAINT MONO (-9525 5850);
DISPLAY INVISIBLE (-9525 5850);
FORCEPROP 1 LAST PATH I104
J 0
(-9475 6000);
DISPLAY 0.978723 (-9475 6000);
PAINT WHITE (-9475 6000);
DISPLAY INVISIBLE (-9475 6000);
FORCEPROP 1 LAST PART_NUMBER CH622KMEB02
J 0
(-9475 5700);
DISPLAY 0.489362 (-9475 5700);
PAINT SKYBLUE (-9475 5700);
DISPLAY INVISIBLE (-9475 5700);
FORCEADD UNIVERSAL_GND..1
(-9125 4675);
FORCEPROP 3 LASTPIN (-9125 4725) SIG_NAME GND\g
J 0
(-9115 4735);
DISPLAY 0.659574 (-9115 4735);
PAINT MONO (-9115 4735);
DISPLAY INVISIBLE (-9115 4735);
FORCEPROP 2 LAST CDS_LIB pure_quanta_power
J 0
(-9125 4675);
PAINT MONO (-9125 4675);
DISPLAY INVISIBLE (-9125 4675);
FORCEPROP 1 LAST HDL_POWER GND
J 1
(-9100 4600);
DISPLAY 0.872340 (-9100 4600);
PAINT GREEN (-9100 4600);
DISPLAY INVISIBLE (-9100 4600);
FORCEPROP 1 LAST PATH I105
J 0
(-9050 4675);
DISPLAY 0.872340 (-9050 4675);
PAINT AQUA (-9050 4675);
DISPLAY INVISIBLE (-9050 4675);
FORCEADD Q_CAP..1
(-9125 5050);
FORCEPROP 1 LAST LOCATION C3896
J 0
(-9075 5150);
DISPLAY 0.489362 (-9075 5150);
PAINT SKYBLUE (-9075 5150);
FORCEPROP 2 LAST $SEC 1
J 0
(-9075 5250);
DISPLAY 0.680851 (-9075 5250);
PAINT MONO (-9075 5250);
DISPLAY INVISIBLE (-9075 5250);
FORCEPROP 2 LAST CDS_SEC 1
J 0
(-9075 5250);
DISPLAY 1.021277 (-9075 5250);
DISPLAY INVISIBLE (-9075 5250);
FORCEPROP 1 LASTPIN (-9125 5150) $PN 1
J 0
(-9115 5130);
DISPLAY 0.489362 (-9115 5130);
FORCEPROP 1 LASTPIN (-9125 4950) $PN 2
J 0
(-9115 4930);
DISPLAY 0.489362 (-9115 4930);
FORCEPROP 1 LAST MATERIAL X6S
J 0
(-9075 4950);
DISPLAY 0.489362 (-9075 4950);
PAINT SKYBLUE (-9075 4950);
FORCEPROP 1 LAST TOLERANCE 20%
J 0
(-9075 5000);
DISPLAY 0.489362 (-9075 5000);
PAINT SKYBLUE (-9075 5000);
FORCEPROP 1 LAST VALUE 22UF
J 0
(-9075 5100);
DISPLAY 0.489362 (-9075 5100);
PAINT SKYBLUE (-9075 5100);
FORCEPROP 1 LAST VOLTAGE 4V
J 0
(-9075 5050);
DISPLAY 0.489362 (-9075 5050);
PAINT SKYBLUE (-9075 5050);
FORCEPROP 1 LAST PACK_TYPE C0402
J 0
(-9075 4850);
DISPLAY 0.489362 (-9075 4850);
PAINT SKYBLUE (-9075 4850);
FORCEPROP 2 LAST CDS_LIB pure_quanta
J 0
(-9125 5050);
PAINT MONO (-9125 5050);
DISPLAY INVISIBLE (-9125 5050);
FORCEPROP 1 LAST PATH I106
J 0
(-9075 5200);
DISPLAY 0.978723 (-9075 5200);
PAINT WHITE (-9075 5200);
DISPLAY INVISIBLE (-9075 5200);
FORCEPROP 1 LAST PART_NUMBER CH622KMEB02
J 0
(-9075 4900);
DISPLAY 0.489362 (-9075 4900);
PAINT SKYBLUE (-9075 4900);
DISPLAY INVISIBLE (-9075 4900);
FORCEADD UNIVERSAL_GND..1
(-9125 5475);
FORCEPROP 3 LASTPIN (-9125 5525) SIG_NAME GND\g
J 0
(-9115 5535);
DISPLAY 0.659574 (-9115 5535);
PAINT MONO (-9115 5535);
DISPLAY INVISIBLE (-9115 5535);
FORCEPROP 2 LAST CDS_LIB pure_quanta_power
J 0
(-9125 5475);
PAINT MONO (-9125 5475);
DISPLAY INVISIBLE (-9125 5475);
FORCEPROP 1 LAST HDL_POWER GND
J 1
(-9100 5400);
DISPLAY 0.872340 (-9100 5400);
PAINT GREEN (-9100 5400);
DISPLAY INVISIBLE (-9100 5400);
FORCEPROP 1 LAST PATH I107
J 0
(-9050 5475);
DISPLAY 0.872340 (-9050 5475);
PAINT AQUA (-9050 5475);
DISPLAY INVISIBLE (-9050 5475);
FORCEADD Q_CAP..1
(-9125 5850);
FORCEPROP 1 LAST LOCATION C2161
J 0
(-9075 5950);
DISPLAY 0.489362 (-9075 5950);
PAINT SKYBLUE (-9075 5950);
FORCEPROP 2 LAST $SEC 1
J 0
(-9075 6050);
DISPLAY 0.680851 (-9075 6050);
PAINT MONO (-9075 6050);
DISPLAY INVISIBLE (-9075 6050);
FORCEPROP 2 LAST CDS_SEC 1
J 0
(-9075 6050);
DISPLAY 1.021277 (-9075 6050);
DISPLAY INVISIBLE (-9075 6050);
FORCEPROP 1 LASTPIN (-9125 5950) $PN 1
J 0
(-9115 5930);
DISPLAY 0.489362 (-9115 5930);
FORCEPROP 1 LASTPIN (-9125 5750) $PN 2
J 0
(-9115 5730);
DISPLAY 0.489362 (-9115 5730);
FORCEPROP 1 LAST MATERIAL X6S
J 0
(-9075 5750);
DISPLAY 0.489362 (-9075 5750);
PAINT SKYBLUE (-9075 5750);
FORCEPROP 1 LAST TOLERANCE 20%
J 0
(-9075 5800);
DISPLAY 0.489362 (-9075 5800);
PAINT SKYBLUE (-9075 5800);
FORCEPROP 1 LAST VALUE 22UF
J 0
(-9075 5900);
DISPLAY 0.489362 (-9075 5900);
PAINT SKYBLUE (-9075 5900);
FORCEPROP 1 LAST VOLTAGE 4V
J 0
(-9075 5850);
DISPLAY 0.489362 (-9075 5850);
PAINT SKYBLUE (-9075 5850);
FORCEPROP 1 LAST PACK_TYPE C0402
J 0
(-9075 5650);
DISPLAY 0.489362 (-9075 5650);
PAINT SKYBLUE (-9075 5650);
FORCEPROP 2 LAST CDS_LIB pure_quanta
J 0
(-9125 5850);
PAINT MONO (-9125 5850);
DISPLAY INVISIBLE (-9125 5850);
FORCEPROP 1 LAST PATH I108
J 0
(-9075 6000);
DISPLAY 0.978723 (-9075 6000);
PAINT WHITE (-9075 6000);
DISPLAY INVISIBLE (-9075 6000);
FORCEPROP 1 LAST PART_NUMBER CH622KMEB02
J 0
(-9075 5700);
DISPLAY 0.489362 (-9075 5700);
PAINT SKYBLUE (-9075 5700);
DISPLAY INVISIBLE (-9075 5700);
FORCEADD Q_CAP..1
(-11325 5850);
FORCEPROP 1 LAST LOCATION C2147
J 0
(-11275 5950);
DISPLAY 0.489362 (-11275 5950);
PAINT SKYBLUE (-11275 5950);
FORCEPROP 2 LAST $SEC 1
J 0
(-11275 6050);
DISPLAY 0.680851 (-11275 6050);
PAINT MONO (-11275 6050);
DISPLAY INVISIBLE (-11275 6050);
FORCEPROP 2 LAST CDS_SEC 1
J 0
(-11275 6050);
DISPLAY 1.021277 (-11275 6050);
DISPLAY INVISIBLE (-11275 6050);
FORCEPROP 1 LASTPIN (-11325 5950) $PN 1
J 0
(-11315 5930);
DISPLAY 0.489362 (-11315 5930);
FORCEPROP 1 LASTPIN (-11325 5750) $PN 2
J 0
(-11315 5730);
DISPLAY 0.489362 (-11315 5730);
FORCEPROP 1 LAST MATERIAL X6S
J 0
(-11275 5750);
DISPLAY 0.489362 (-11275 5750);
PAINT SKYBLUE (-11275 5750);
FORCEPROP 1 LAST TOLERANCE 20%
J 0
(-11275 5800);
DISPLAY 0.489362 (-11275 5800);
PAINT SKYBLUE (-11275 5800);
FORCEPROP 1 LAST VALUE 22UF
J 0
(-11275 5900);
DISPLAY 0.489362 (-11275 5900);
PAINT SKYBLUE (-11275 5900);
FORCEPROP 1 LAST VOLTAGE 4V
J 0
(-11275 5850);
DISPLAY 0.489362 (-11275 5850);
PAINT SKYBLUE (-11275 5850);
FORCEPROP 1 LAST PACK_TYPE C0402
J 0
(-11275 5650);
DISPLAY 0.489362 (-11275 5650);
PAINT SKYBLUE (-11275 5650);
FORCEPROP 2 LAST CDS_LIB pure_quanta
J 0
(-11325 5850);
PAINT MONO (-11325 5850);
DISPLAY INVISIBLE (-11325 5850);
FORCEPROP 1 LAST PATH I109
J 0
(-11275 6000);
DISPLAY 0.978723 (-11275 6000);
PAINT WHITE (-11275 6000);
DISPLAY INVISIBLE (-11275 6000);
FORCEPROP 1 LAST PART_NUMBER CH622KMEB02
J 0
(-11275 5700);
DISPLAY 0.489362 (-11275 5700);
PAINT SKYBLUE (-11275 5700);
DISPLAY INVISIBLE (-11275 5700);
FORCEADD Q_CAP..1
(-13125 1600);
FORCEPROP 1 LAST LOCATION C2133
J 0
(-13075 1700);
DISPLAY 0.489362 (-13075 1700);
PAINT SKYBLUE (-13075 1700);
FORCEPROP 2 LAST $SEC 1
J 0
(-13075 1800);
DISPLAY 0.680851 (-13075 1800);
PAINT MONO (-13075 1800);
DISPLAY INVISIBLE (-13075 1800);
FORCEPROP 2 LAST CDS_SEC 1
J 0
(-13075 1800);
DISPLAY 1.021277 (-13075 1800);
DISPLAY INVISIBLE (-13075 1800);
FORCEPROP 1 LASTPIN (-13125 1700) $PN 1
J 0
(-13115 1680);
DISPLAY 0.489362 (-13115 1680);
FORCEPROP 1 LASTPIN (-13125 1500) $PN 2
J 0
(-13115 1480);
DISPLAY 0.489362 (-13115 1480);
FORCEPROP 1 LAST MATERIAL X6S
J 0
(-13075 1500);
DISPLAY 0.489362 (-13075 1500);
PAINT SKYBLUE (-13075 1500);
FORCEPROP 1 LAST TOLERANCE 20%
J 0
(-13075 1550);
DISPLAY 0.489362 (-13075 1550);
PAINT SKYBLUE (-13075 1550);
FORCEPROP 1 LAST VALUE 22UF
J 0
(-13075 1650);
DISPLAY 0.489362 (-13075 1650);
PAINT SKYBLUE (-13075 1650);
FORCEPROP 1 LAST VOLTAGE 4V
J 0
(-13075 1600);
DISPLAY 0.489362 (-13075 1600);
PAINT SKYBLUE (-13075 1600);
FORCEPROP 1 LAST PACK_TYPE C0402
J 0
(-13075 1400);
DISPLAY 0.489362 (-13075 1400);
PAINT SKYBLUE (-13075 1400);
FORCEPROP 2 LAST CDS_LIB pure_quanta
J 0
(-13125 1600);
PAINT MONO (-13125 1600);
DISPLAY INVISIBLE (-13125 1600);
FORCEPROP 1 LAST PATH I110
J 0
(-13075 1750);
DISPLAY 0.978723 (-13075 1750);
PAINT WHITE (-13075 1750);
DISPLAY INVISIBLE (-13075 1750);
FORCEPROP 1 LAST PART_NUMBER CH622KMEB02
J 0
(-13075 1450);
DISPLAY 0.489362 (-13075 1450);
PAINT SKYBLUE (-13075 1450);
DISPLAY INVISIBLE (-13075 1450);
FORCEADD UNIVERSAL_POWER..1
(-13125 1875);
FORCEPROP 3 LASTPIN (-13125 1825) SIG_NAME PVDD11_S3_P0\g
J 0
(-13115 1835);
DISPLAY 0.659574 (-13115 1835);
PAINT MONO (-13115 1835);
DISPLAY INVISIBLE (-13115 1835);
FORCEPROP 1 LAST HDL_POWER PVDD11_S3_P0
J 1
(-13125 1925);
DISPLAY 0.489362 (-13125 1925);
PAINT GREEN (-13125 1925);
FORCEPROP 2 LAST CDS_LIB pure_quanta_power
J 0
(-13125 1875);
DISPLAY INVISIBLE (-13125 1875);
FORCEPROP 1 LAST PATH I111
J 0
(-13075 1900);
DISPLAY 0.872340 (-13075 1900);
PAINT AQUA (-13075 1900);
DISPLAY INVISIBLE (-13075 1900);
FORCEADD Q_CAP..1
(-12675 1600);
FORCEPROP 1 LAST LOCATION C2138
J 0
(-12625 1700);
DISPLAY 0.489362 (-12625 1700);
PAINT SKYBLUE (-12625 1700);
FORCEPROP 2 LAST $SEC 1
J 0
(-12625 1800);
DISPLAY 0.680851 (-12625 1800);
PAINT MONO (-12625 1800);
DISPLAY INVISIBLE (-12625 1800);
FORCEPROP 2 LAST CDS_SEC 1
J 0
(-12625 1800);
DISPLAY 1.021277 (-12625 1800);
DISPLAY INVISIBLE (-12625 1800);
FORCEPROP 1 LASTPIN (-12675 1700) $PN 1
J 0
(-12665 1680);
DISPLAY 0.489362 (-12665 1680);
FORCEPROP 1 LASTPIN (-12675 1500) $PN 2
J 0
(-12665 1480);
DISPLAY 0.489362 (-12665 1480);
FORCEPROP 1 LAST MATERIAL X6S
J 0
(-12625 1500);
DISPLAY 0.489362 (-12625 1500);
PAINT SKYBLUE (-12625 1500);
FORCEPROP 1 LAST TOLERANCE 20%
J 0
(-12625 1550);
DISPLAY 0.489362 (-12625 1550);
PAINT SKYBLUE (-12625 1550);
FORCEPROP 1 LAST VALUE 22UF
J 0
(-12625 1650);
DISPLAY 0.489362 (-12625 1650);
PAINT SKYBLUE (-12625 1650);
FORCEPROP 1 LAST VOLTAGE 4V
J 0
(-12625 1600);
DISPLAY 0.489362 (-12625 1600);
PAINT SKYBLUE (-12625 1600);
FORCEPROP 1 LAST PACK_TYPE C0402
J 0
(-12625 1400);
DISPLAY 0.489362 (-12625 1400);
PAINT SKYBLUE (-12625 1400);
FORCEPROP 2 LAST CDS_LIB pure_quanta
J 0
(-12675 1600);
PAINT MONO (-12675 1600);
DISPLAY INVISIBLE (-12675 1600);
FORCEPROP 1 LAST PATH I112
J 0
(-12625 1750);
DISPLAY 0.978723 (-12625 1750);
PAINT WHITE (-12625 1750);
DISPLAY INVISIBLE (-12625 1750);
FORCEPROP 1 LAST PART_NUMBER CH622KMEB02
J 0
(-12625 1450);
DISPLAY 0.489362 (-12625 1450);
PAINT SKYBLUE (-12625 1450);
DISPLAY INVISIBLE (-12625 1450);
FORCEADD Q_CAP..1
(-13125 2350);
FORCEPROP 1 LAST LOCATION C2132
J 0
(-13075 2450);
DISPLAY 0.489362 (-13075 2450);
PAINT SKYBLUE (-13075 2450);
FORCEPROP 2 LAST $SEC 1
J 0
(-13075 2550);
DISPLAY 0.680851 (-13075 2550);
PAINT MONO (-13075 2550);
DISPLAY INVISIBLE (-13075 2550);
FORCEPROP 2 LAST CDS_SEC 1
J 0
(-13075 2550);
DISPLAY 1.021277 (-13075 2550);
DISPLAY INVISIBLE (-13075 2550);
FORCEPROP 1 LASTPIN (-13125 2450) $PN 1
J 0
(-13115 2430);
DISPLAY 0.489362 (-13115 2430);
FORCEPROP 1 LASTPIN (-13125 2250) $PN 2
J 0
(-13115 2230);
DISPLAY 0.489362 (-13115 2230);
FORCEPROP 1 LAST MATERIAL X6S
J 0
(-13075 2250);
DISPLAY 0.489362 (-13075 2250);
PAINT SKYBLUE (-13075 2250);
FORCEPROP 1 LAST TOLERANCE 20%
J 0
(-13075 2300);
DISPLAY 0.489362 (-13075 2300);
PAINT SKYBLUE (-13075 2300);
FORCEPROP 1 LAST VALUE 22UF
J 0
(-13075 2400);
DISPLAY 0.489362 (-13075 2400);
PAINT SKYBLUE (-13075 2400);
FORCEPROP 1 LAST VOLTAGE 4V
J 0
(-13075 2350);
DISPLAY 0.489362 (-13075 2350);
PAINT SKYBLUE (-13075 2350);
FORCEPROP 1 LAST PACK_TYPE C0402
J 0
(-13075 2150);
DISPLAY 0.489362 (-13075 2150);
PAINT SKYBLUE (-13075 2150);
FORCEPROP 2 LAST CDS_LIB pure_quanta
J 0
(-13125 2350);
PAINT MONO (-13125 2350);
DISPLAY INVISIBLE (-13125 2350);
FORCEPROP 1 LAST PATH I113
J 0
(-13075 2500);
DISPLAY 0.978723 (-13075 2500);
PAINT WHITE (-13075 2500);
DISPLAY INVISIBLE (-13075 2500);
FORCEPROP 1 LAST PART_NUMBER CH622KMEB02
J 0
(-13075 2200);
DISPLAY 0.489362 (-13075 2200);
PAINT SKYBLUE (-13075 2200);
DISPLAY INVISIBLE (-13075 2200);
FORCEADD UNIVERSAL_POWER..1
(-13125 2625);
FORCEPROP 3 LASTPIN (-13125 2575) SIG_NAME PVDD11_S3_P0\g
J 0
(-13115 2585);
DISPLAY 0.659574 (-13115 2585);
PAINT MONO (-13115 2585);
DISPLAY INVISIBLE (-13115 2585);
FORCEPROP 1 LAST HDL_POWER PVDD11_S3_P0
J 1
(-13125 2675);
DISPLAY 0.489362 (-13125 2675);
PAINT GREEN (-13125 2675);
FORCEPROP 2 LAST CDS_LIB pure_quanta_power
J 0
(-13125 2625);
DISPLAY INVISIBLE (-13125 2625);
FORCEPROP 1 LAST PATH I114
J 0
(-13075 2650);
DISPLAY 0.872340 (-13075 2650);
PAINT AQUA (-13075 2650);
DISPLAY INVISIBLE (-13075 2650);
FORCEADD Q_CAP..1
(-12675 2350);
FORCEPROP 1 LAST LOCATION C2137
J 0
(-12625 2450);
DISPLAY 0.489362 (-12625 2450);
PAINT SKYBLUE (-12625 2450);
FORCEPROP 2 LAST $SEC 1
J 0
(-12625 2550);
DISPLAY 0.680851 (-12625 2550);
PAINT MONO (-12625 2550);
DISPLAY INVISIBLE (-12625 2550);
FORCEPROP 2 LAST CDS_SEC 1
J 0
(-12625 2550);
DISPLAY 1.021277 (-12625 2550);
DISPLAY INVISIBLE (-12625 2550);
FORCEPROP 1 LASTPIN (-12675 2450) $PN 1
J 0
(-12665 2430);
DISPLAY 0.489362 (-12665 2430);
FORCEPROP 1 LASTPIN (-12675 2250) $PN 2
J 0
(-12665 2230);
DISPLAY 0.489362 (-12665 2230);
FORCEPROP 1 LAST MATERIAL X6S
J 0
(-12625 2250);
DISPLAY 0.489362 (-12625 2250);
PAINT SKYBLUE (-12625 2250);
FORCEPROP 1 LAST TOLERANCE 20%
J 0
(-12625 2300);
DISPLAY 0.489362 (-12625 2300);
PAINT SKYBLUE (-12625 2300);
FORCEPROP 1 LAST VALUE 22UF
J 0
(-12625 2400);
DISPLAY 0.489362 (-12625 2400);
PAINT SKYBLUE (-12625 2400);
FORCEPROP 1 LAST VOLTAGE 4V
J 0
(-12625 2350);
DISPLAY 0.489362 (-12625 2350);
PAINT SKYBLUE (-12625 2350);
FORCEPROP 1 LAST PACK_TYPE C0402
J 0
(-12625 2150);
DISPLAY 0.489362 (-12625 2150);
PAINT SKYBLUE (-12625 2150);
FORCEPROP 2 LAST CDS_LIB pure_quanta
J 0
(-12675 2350);
PAINT MONO (-12675 2350);
DISPLAY INVISIBLE (-12675 2350);
FORCEPROP 1 LAST PATH I115
J 0
(-12625 2500);
DISPLAY 0.978723 (-12625 2500);
PAINT WHITE (-12625 2500);
DISPLAY INVISIBLE (-12625 2500);
FORCEPROP 1 LAST PART_NUMBER CH622KMEB02
J 0
(-12625 2200);
DISPLAY 0.489362 (-12625 2200);
PAINT SKYBLUE (-12625 2200);
DISPLAY INVISIBLE (-12625 2200);
FORCEADD Q_CAP..1
(-12225 1600);
FORCEPROP 1 LAST LOCATION C3890
J 0
(-12175 1700);
DISPLAY 0.489362 (-12175 1700);
PAINT SKYBLUE (-12175 1700);
FORCEPROP 2 LAST $SEC 1
J 0
(-12175 1800);
DISPLAY 0.680851 (-12175 1800);
PAINT MONO (-12175 1800);
DISPLAY INVISIBLE (-12175 1800);
FORCEPROP 2 LAST CDS_SEC 1
J 0
(-12175 1800);
DISPLAY 1.021277 (-12175 1800);
DISPLAY INVISIBLE (-12175 1800);
FORCEPROP 1 LASTPIN (-12225 1700) $PN 1
J 0
(-12215 1680);
DISPLAY 0.489362 (-12215 1680);
FORCEPROP 1 LASTPIN (-12225 1500) $PN 2
J 0
(-12215 1480);
DISPLAY 0.489362 (-12215 1480);
FORCEPROP 1 LAST MATERIAL X6S
J 0
(-12175 1500);
DISPLAY 0.489362 (-12175 1500);
PAINT SKYBLUE (-12175 1500);
FORCEPROP 1 LAST TOLERANCE 20%
J 0
(-12175 1550);
DISPLAY 0.489362 (-12175 1550);
PAINT SKYBLUE (-12175 1550);
FORCEPROP 1 LAST VALUE 22UF
J 0
(-12175 1650);
DISPLAY 0.489362 (-12175 1650);
PAINT SKYBLUE (-12175 1650);
FORCEPROP 1 LAST VOLTAGE 4V
J 0
(-12175 1600);
DISPLAY 0.489362 (-12175 1600);
PAINT SKYBLUE (-12175 1600);
FORCEPROP 1 LAST PACK_TYPE C0402
J 0
(-12175 1400);
DISPLAY 0.489362 (-12175 1400);
PAINT SKYBLUE (-12175 1400);
FORCEPROP 2 LAST CDS_LIB pure_quanta
J 0
(-12225 1600);
PAINT MONO (-12225 1600);
DISPLAY INVISIBLE (-12225 1600);
FORCEPROP 1 LAST PATH I116
J 0
(-12175 1750);
DISPLAY 0.978723 (-12175 1750);
PAINT WHITE (-12175 1750);
DISPLAY INVISIBLE (-12175 1750);
FORCEPROP 1 LAST PART_NUMBER CH622KMEB02
J 0
(-12175 1450);
DISPLAY 0.489362 (-12175 1450);
PAINT SKYBLUE (-12175 1450);
DISPLAY INVISIBLE (-12175 1450);
FORCEADD Q_CAP..1
(-11775 1600);
FORCEPROP 1 LAST LOCATION C3891
J 0
(-11725 1700);
DISPLAY 0.489362 (-11725 1700);
PAINT SKYBLUE (-11725 1700);
FORCEPROP 2 LAST $SEC 1
J 0
(-11725 1800);
DISPLAY 0.680851 (-11725 1800);
PAINT MONO (-11725 1800);
DISPLAY INVISIBLE (-11725 1800);
FORCEPROP 2 LAST CDS_SEC 1
J 0
(-11725 1800);
DISPLAY 1.021277 (-11725 1800);
DISPLAY INVISIBLE (-11725 1800);
FORCEPROP 1 LASTPIN (-11775 1700) $PN 1
J 0
(-11765 1680);
DISPLAY 0.489362 (-11765 1680);
FORCEPROP 1 LASTPIN (-11775 1500) $PN 2
J 0
(-11765 1480);
DISPLAY 0.489362 (-11765 1480);
FORCEPROP 1 LAST MATERIAL X6S
J 0
(-11725 1500);
DISPLAY 0.489362 (-11725 1500);
PAINT SKYBLUE (-11725 1500);
FORCEPROP 1 LAST TOLERANCE 20%
J 0
(-11725 1550);
DISPLAY 0.489362 (-11725 1550);
PAINT SKYBLUE (-11725 1550);
FORCEPROP 1 LAST VALUE 22UF
J 0
(-11725 1650);
DISPLAY 0.489362 (-11725 1650);
PAINT SKYBLUE (-11725 1650);
FORCEPROP 1 LAST VOLTAGE 4V
J 0
(-11725 1600);
DISPLAY 0.489362 (-11725 1600);
PAINT SKYBLUE (-11725 1600);
FORCEPROP 1 LAST PACK_TYPE C0402
J 0
(-11725 1400);
DISPLAY 0.489362 (-11725 1400);
PAINT SKYBLUE (-11725 1400);
FORCEPROP 2 LAST CDS_LIB pure_quanta
J 0
(-11775 1600);
PAINT MONO (-11775 1600);
DISPLAY INVISIBLE (-11775 1600);
FORCEPROP 1 LAST PATH I117
J 0
(-11725 1750);
DISPLAY 0.978723 (-11725 1750);
PAINT WHITE (-11725 1750);
DISPLAY INVISIBLE (-11725 1750);
FORCEPROP 1 LAST PART_NUMBER CH622KMEB02
J 0
(-11725 1450);
DISPLAY 0.489362 (-11725 1450);
PAINT SKYBLUE (-11725 1450);
DISPLAY INVISIBLE (-11725 1450);
FORCEADD Q_CAP..1
(-11325 1600);
FORCEPROP 1 LAST LOCATION C3892
J 0
(-11275 1700);
DISPLAY 0.489362 (-11275 1700);
PAINT SKYBLUE (-11275 1700);
FORCEPROP 2 LAST $SEC 1
J 0
(-11275 1800);
DISPLAY 0.680851 (-11275 1800);
PAINT MONO (-11275 1800);
DISPLAY INVISIBLE (-11275 1800);
FORCEPROP 2 LAST CDS_SEC 1
J 0
(-11275 1800);
DISPLAY 1.021277 (-11275 1800);
DISPLAY INVISIBLE (-11275 1800);
FORCEPROP 1 LASTPIN (-11325 1700) $PN 1
J 0
(-11315 1680);
DISPLAY 0.489362 (-11315 1680);
FORCEPROP 1 LASTPIN (-11325 1500) $PN 2
J 0
(-11315 1480);
DISPLAY 0.489362 (-11315 1480);
FORCEPROP 1 LAST MATERIAL X6S
J 0
(-11275 1500);
DISPLAY 0.489362 (-11275 1500);
PAINT SKYBLUE (-11275 1500);
FORCEPROP 1 LAST TOLERANCE 20%
J 0
(-11275 1550);
DISPLAY 0.489362 (-11275 1550);
PAINT SKYBLUE (-11275 1550);
FORCEPROP 1 LAST VALUE 22UF
J 0
(-11275 1650);
DISPLAY 0.489362 (-11275 1650);
PAINT SKYBLUE (-11275 1650);
FORCEPROP 1 LAST VOLTAGE 4V
J 0
(-11275 1600);
DISPLAY 0.489362 (-11275 1600);
PAINT SKYBLUE (-11275 1600);
FORCEPROP 1 LAST PACK_TYPE C0402
J 0
(-11275 1400);
DISPLAY 0.489362 (-11275 1400);
PAINT SKYBLUE (-11275 1400);
FORCEPROP 2 LAST CDS_LIB pure_quanta
J 0
(-11325 1600);
PAINT MONO (-11325 1600);
DISPLAY INVISIBLE (-11325 1600);
FORCEPROP 1 LAST PATH I118
J 0
(-11275 1750);
DISPLAY 0.978723 (-11275 1750);
PAINT WHITE (-11275 1750);
DISPLAY INVISIBLE (-11275 1750);
FORCEPROP 1 LAST PART_NUMBER CH622KMEB02
J 0
(-11275 1450);
DISPLAY 0.489362 (-11275 1450);
PAINT SKYBLUE (-11275 1450);
DISPLAY INVISIBLE (-11275 1450);
FORCEADD UNIVERSAL_GND..1
(-10875 1225);
FORCEPROP 3 LASTPIN (-10875 1275) SIG_NAME GND\g
J 0
(-10865 1285);
DISPLAY 0.659574 (-10865 1285);
PAINT MONO (-10865 1285);
DISPLAY INVISIBLE (-10865 1285);
FORCEPROP 2 LAST CDS_LIB pure_quanta_power
J 0
(-10875 1225);
PAINT MONO (-10875 1225);
DISPLAY INVISIBLE (-10875 1225);
FORCEPROP 1 LAST HDL_POWER GND
J 1
(-10850 1150);
DISPLAY 0.872340 (-10850 1150);
PAINT GREEN (-10850 1150);
DISPLAY INVISIBLE (-10850 1150);
FORCEPROP 1 LAST PATH I119
J 0
(-10800 1225);
DISPLAY 0.872340 (-10800 1225);
PAINT AQUA (-10800 1225);
DISPLAY INVISIBLE (-10800 1225);
FORCEADD Q_CAP..1
(-10875 1600);
FORCEPROP 1 LAST LOCATION C3893
J 0
(-10825 1700);
DISPLAY 0.489362 (-10825 1700);
PAINT SKYBLUE (-10825 1700);
FORCEPROP 2 LAST $SEC 1
J 0
(-10825 1800);
DISPLAY 0.680851 (-10825 1800);
PAINT MONO (-10825 1800);
DISPLAY INVISIBLE (-10825 1800);
FORCEPROP 2 LAST CDS_SEC 1
J 0
(-10825 1800);
DISPLAY 1.021277 (-10825 1800);
DISPLAY INVISIBLE (-10825 1800);
FORCEPROP 1 LASTPIN (-10875 1700) $PN 1
J 0
(-10865 1680);
DISPLAY 0.489362 (-10865 1680);
FORCEPROP 1 LASTPIN (-10875 1500) $PN 2
J 0
(-10865 1480);
DISPLAY 0.489362 (-10865 1480);
FORCEPROP 1 LAST MATERIAL X6S
J 0
(-10825 1500);
DISPLAY 0.489362 (-10825 1500);
PAINT SKYBLUE (-10825 1500);
FORCEPROP 1 LAST TOLERANCE 20%
J 0
(-10825 1550);
DISPLAY 0.489362 (-10825 1550);
PAINT SKYBLUE (-10825 1550);
FORCEPROP 1 LAST VALUE 22UF
J 0
(-10825 1650);
DISPLAY 0.489362 (-10825 1650);
PAINT SKYBLUE (-10825 1650);
FORCEPROP 1 LAST VOLTAGE 4V
J 0
(-10825 1600);
DISPLAY 0.489362 (-10825 1600);
PAINT SKYBLUE (-10825 1600);
FORCEPROP 1 LAST PACK_TYPE C0402
J 0
(-10825 1400);
DISPLAY 0.489362 (-10825 1400);
PAINT SKYBLUE (-10825 1400);
FORCEPROP 2 LAST CDS_LIB pure_quanta
J 0
(-10875 1600);
PAINT MONO (-10875 1600);
DISPLAY INVISIBLE (-10875 1600);
FORCEPROP 1 LAST PATH I120
J 0
(-10825 1750);
DISPLAY 0.978723 (-10825 1750);
PAINT WHITE (-10825 1750);
DISPLAY INVISIBLE (-10825 1750);
FORCEPROP 1 LAST PART_NUMBER CH622KMEB02
J 0
(-10825 1450);
DISPLAY 0.489362 (-10825 1450);
PAINT SKYBLUE (-10825 1450);
DISPLAY INVISIBLE (-10825 1450);
FORCEADD Q_CAP..1
(-12225 2350);
FORCEPROP 1 LAST LOCATION C2142
J 0
(-12175 2450);
DISPLAY 0.489362 (-12175 2450);
PAINT SKYBLUE (-12175 2450);
FORCEPROP 2 LAST $SEC 1
J 0
(-12175 2550);
DISPLAY 0.680851 (-12175 2550);
PAINT MONO (-12175 2550);
DISPLAY INVISIBLE (-12175 2550);
FORCEPROP 2 LAST CDS_SEC 1
J 0
(-12175 2550);
DISPLAY 1.021277 (-12175 2550);
DISPLAY INVISIBLE (-12175 2550);
FORCEPROP 1 LASTPIN (-12225 2450) $PN 1
J 0
(-12215 2430);
DISPLAY 0.489362 (-12215 2430);
FORCEPROP 1 LASTPIN (-12225 2250) $PN 2
J 0
(-12215 2230);
DISPLAY 0.489362 (-12215 2230);
FORCEPROP 1 LAST MATERIAL X6S
J 0
(-12175 2250);
DISPLAY 0.489362 (-12175 2250);
PAINT SKYBLUE (-12175 2250);
FORCEPROP 1 LAST TOLERANCE 20%
J 0
(-12175 2300);
DISPLAY 0.489362 (-12175 2300);
PAINT SKYBLUE (-12175 2300);
FORCEPROP 1 LAST VALUE 22UF
J 0
(-12175 2400);
DISPLAY 0.489362 (-12175 2400);
PAINT SKYBLUE (-12175 2400);
FORCEPROP 1 LAST VOLTAGE 4V
J 0
(-12175 2350);
DISPLAY 0.489362 (-12175 2350);
PAINT SKYBLUE (-12175 2350);
FORCEPROP 1 LAST PACK_TYPE C0402
J 0
(-12175 2150);
DISPLAY 0.489362 (-12175 2150);
PAINT SKYBLUE (-12175 2150);
FORCEPROP 2 LAST CDS_LIB pure_quanta
J 0
(-12225 2350);
PAINT MONO (-12225 2350);
DISPLAY INVISIBLE (-12225 2350);
FORCEPROP 1 LAST PATH I121
J 0
(-12175 2500);
DISPLAY 0.978723 (-12175 2500);
PAINT WHITE (-12175 2500);
DISPLAY INVISIBLE (-12175 2500);
FORCEPROP 1 LAST PART_NUMBER CH622KMEB02
J 0
(-12175 2200);
DISPLAY 0.489362 (-12175 2200);
PAINT SKYBLUE (-12175 2200);
DISPLAY INVISIBLE (-12175 2200);
FORCEADD Q_CAP..1
(-11775 2350);
FORCEPROP 1 LAST LOCATION C2146
J 0
(-11725 2450);
DISPLAY 0.489362 (-11725 2450);
PAINT SKYBLUE (-11725 2450);
FORCEPROP 2 LAST $SEC 1
J 0
(-11725 2550);
DISPLAY 0.680851 (-11725 2550);
PAINT MONO (-11725 2550);
DISPLAY INVISIBLE (-11725 2550);
FORCEPROP 2 LAST CDS_SEC 1
J 0
(-11725 2550);
DISPLAY 1.021277 (-11725 2550);
DISPLAY INVISIBLE (-11725 2550);
FORCEPROP 1 LASTPIN (-11775 2450) $PN 1
J 0
(-11765 2430);
DISPLAY 0.489362 (-11765 2430);
FORCEPROP 1 LASTPIN (-11775 2250) $PN 2
J 0
(-11765 2230);
DISPLAY 0.489362 (-11765 2230);
FORCEPROP 1 LAST MATERIAL X6S
J 0
(-11725 2250);
DISPLAY 0.489362 (-11725 2250);
PAINT SKYBLUE (-11725 2250);
FORCEPROP 1 LAST TOLERANCE 20%
J 0
(-11725 2300);
DISPLAY 0.489362 (-11725 2300);
PAINT SKYBLUE (-11725 2300);
FORCEPROP 1 LAST VALUE 22UF
J 0
(-11725 2400);
DISPLAY 0.489362 (-11725 2400);
PAINT SKYBLUE (-11725 2400);
FORCEPROP 1 LAST VOLTAGE 4V
J 0
(-11725 2350);
DISPLAY 0.489362 (-11725 2350);
PAINT SKYBLUE (-11725 2350);
FORCEPROP 1 LAST PACK_TYPE C0402
J 0
(-11725 2150);
DISPLAY 0.489362 (-11725 2150);
PAINT SKYBLUE (-11725 2150);
FORCEPROP 2 LAST CDS_LIB pure_quanta
J 0
(-11775 2350);
PAINT MONO (-11775 2350);
DISPLAY INVISIBLE (-11775 2350);
FORCEPROP 1 LAST PATH I122
J 0
(-11725 2500);
DISPLAY 0.978723 (-11725 2500);
PAINT WHITE (-11725 2500);
DISPLAY INVISIBLE (-11725 2500);
FORCEPROP 1 LAST PART_NUMBER CH622KMEB02
J 0
(-11725 2200);
DISPLAY 0.489362 (-11725 2200);
PAINT SKYBLUE (-11725 2200);
DISPLAY INVISIBLE (-11725 2200);
FORCEADD Q_CAP..1
(-11325 2350);
FORCEPROP 1 LAST LOCATION C2150
J 0
(-11275 2450);
DISPLAY 0.489362 (-11275 2450);
PAINT SKYBLUE (-11275 2450);
FORCEPROP 2 LAST $SEC 1
J 0
(-11275 2550);
DISPLAY 0.680851 (-11275 2550);
PAINT MONO (-11275 2550);
DISPLAY INVISIBLE (-11275 2550);
FORCEPROP 2 LAST CDS_SEC 1
J 0
(-11275 2550);
DISPLAY 1.021277 (-11275 2550);
DISPLAY INVISIBLE (-11275 2550);
FORCEPROP 1 LASTPIN (-11325 2450) $PN 1
J 0
(-11315 2430);
DISPLAY 0.489362 (-11315 2430);
FORCEPROP 1 LASTPIN (-11325 2250) $PN 2
J 0
(-11315 2230);
DISPLAY 0.489362 (-11315 2230);
FORCEPROP 1 LAST MATERIAL X6S
J 0
(-11275 2250);
DISPLAY 0.489362 (-11275 2250);
PAINT SKYBLUE (-11275 2250);
FORCEPROP 1 LAST TOLERANCE 20%
J 0
(-11275 2300);
DISPLAY 0.489362 (-11275 2300);
PAINT SKYBLUE (-11275 2300);
FORCEPROP 1 LAST VALUE 22UF
J 0
(-11275 2400);
DISPLAY 0.489362 (-11275 2400);
PAINT SKYBLUE (-11275 2400);
FORCEPROP 1 LAST VOLTAGE 4V
J 0
(-11275 2350);
DISPLAY 0.489362 (-11275 2350);
PAINT SKYBLUE (-11275 2350);
FORCEPROP 1 LAST PACK_TYPE C0402
J 0
(-11275 2150);
DISPLAY 0.489362 (-11275 2150);
PAINT SKYBLUE (-11275 2150);
FORCEPROP 2 LAST CDS_LIB pure_quanta
J 0
(-11325 2350);
PAINT MONO (-11325 2350);
DISPLAY INVISIBLE (-11325 2350);
FORCEPROP 1 LAST PATH I123
J 0
(-11275 2500);
DISPLAY 0.978723 (-11275 2500);
PAINT WHITE (-11275 2500);
DISPLAY INVISIBLE (-11275 2500);
FORCEPROP 1 LAST PART_NUMBER CH622KMEB02
J 0
(-11275 2200);
DISPLAY 0.489362 (-11275 2200);
PAINT SKYBLUE (-11275 2200);
DISPLAY INVISIBLE (-11275 2200);
FORCEADD Q_CAP..1
(-10875 2350);
FORCEPROP 1 LAST LOCATION C2153
J 0
(-10825 2450);
DISPLAY 0.489362 (-10825 2450);
PAINT SKYBLUE (-10825 2450);
FORCEPROP 2 LAST $SEC 1
J 0
(-10825 2550);
DISPLAY 0.680851 (-10825 2550);
PAINT MONO (-10825 2550);
DISPLAY INVISIBLE (-10825 2550);
FORCEPROP 2 LAST CDS_SEC 1
J 0
(-10825 2550);
DISPLAY 1.021277 (-10825 2550);
DISPLAY INVISIBLE (-10825 2550);
FORCEPROP 1 LASTPIN (-10875 2450) $PN 1
J 0
(-10865 2430);
DISPLAY 0.489362 (-10865 2430);
FORCEPROP 1 LASTPIN (-10875 2250) $PN 2
J 0
(-10865 2230);
DISPLAY 0.489362 (-10865 2230);
FORCEPROP 1 LAST MATERIAL X6S
J 0
(-10825 2250);
DISPLAY 0.489362 (-10825 2250);
PAINT SKYBLUE (-10825 2250);
FORCEPROP 1 LAST TOLERANCE 20%
J 0
(-10825 2300);
DISPLAY 0.489362 (-10825 2300);
PAINT SKYBLUE (-10825 2300);
FORCEPROP 1 LAST VALUE 22UF
J 0
(-10825 2400);
DISPLAY 0.489362 (-10825 2400);
PAINT SKYBLUE (-10825 2400);
FORCEPROP 1 LAST VOLTAGE 4V
J 0
(-10825 2350);
DISPLAY 0.489362 (-10825 2350);
PAINT SKYBLUE (-10825 2350);
FORCEPROP 1 LAST PACK_TYPE C0402
J 0
(-10825 2150);
DISPLAY 0.489362 (-10825 2150);
PAINT SKYBLUE (-10825 2150);
FORCEPROP 2 LAST CDS_LIB pure_quanta
J 0
(-10875 2350);
PAINT MONO (-10875 2350);
DISPLAY INVISIBLE (-10875 2350);
FORCEPROP 1 LAST PATH I124
J 0
(-10825 2500);
DISPLAY 0.978723 (-10825 2500);
PAINT WHITE (-10825 2500);
DISPLAY INVISIBLE (-10825 2500);
FORCEPROP 1 LAST PART_NUMBER CH622KMEB02
J 0
(-10825 2200);
DISPLAY 0.489362 (-10825 2200);
PAINT SKYBLUE (-10825 2200);
DISPLAY INVISIBLE (-10825 2200);
FORCEADD Q_CAP..1
(-10425 2350);
FORCEPROP 1 LAST LOCATION C2156
J 0
(-10375 2450);
DISPLAY 0.489362 (-10375 2450);
PAINT SKYBLUE (-10375 2450);
FORCEPROP 2 LAST $SEC 1
J 0
(-10375 2550);
DISPLAY 0.680851 (-10375 2550);
PAINT MONO (-10375 2550);
DISPLAY INVISIBLE (-10375 2550);
FORCEPROP 2 LAST CDS_SEC 1
J 0
(-10375 2550);
DISPLAY 1.021277 (-10375 2550);
DISPLAY INVISIBLE (-10375 2550);
FORCEPROP 1 LASTPIN (-10425 2450) $PN 1
J 0
(-10415 2430);
DISPLAY 0.489362 (-10415 2430);
FORCEPROP 1 LASTPIN (-10425 2250) $PN 2
J 0
(-10415 2230);
DISPLAY 0.489362 (-10415 2230);
FORCEPROP 1 LAST MATERIAL X6S
J 0
(-10375 2250);
DISPLAY 0.489362 (-10375 2250);
PAINT SKYBLUE (-10375 2250);
FORCEPROP 1 LAST TOLERANCE 20%
J 0
(-10375 2300);
DISPLAY 0.489362 (-10375 2300);
PAINT SKYBLUE (-10375 2300);
FORCEPROP 1 LAST VALUE 22UF
J 0
(-10375 2400);
DISPLAY 0.489362 (-10375 2400);
PAINT SKYBLUE (-10375 2400);
FORCEPROP 1 LAST VOLTAGE 4V
J 0
(-10375 2350);
DISPLAY 0.489362 (-10375 2350);
PAINT SKYBLUE (-10375 2350);
FORCEPROP 1 LAST PACK_TYPE C0402
J 0
(-10375 2150);
DISPLAY 0.489362 (-10375 2150);
PAINT SKYBLUE (-10375 2150);
FORCEPROP 2 LAST CDS_LIB pure_quanta
J 0
(-10425 2350);
PAINT MONO (-10425 2350);
DISPLAY INVISIBLE (-10425 2350);
FORCEPROP 1 LAST PATH I125
J 0
(-10375 2500);
DISPLAY 0.978723 (-10375 2500);
PAINT WHITE (-10375 2500);
DISPLAY INVISIBLE (-10375 2500);
FORCEPROP 1 LAST PART_NUMBER CH622KMEB02
J 0
(-10375 2200);
DISPLAY 0.489362 (-10375 2200);
PAINT SKYBLUE (-10375 2200);
DISPLAY INVISIBLE (-10375 2200);
FORCEADD UNIVERSAL_GND..1
(-9125 1975);
FORCEPROP 3 LASTPIN (-9125 2025) SIG_NAME GND\g
J 0
(-9115 2035);
DISPLAY 0.659574 (-9115 2035);
PAINT MONO (-9115 2035);
DISPLAY INVISIBLE (-9115 2035);
FORCEPROP 2 LAST CDS_LIB pure_quanta_power
J 0
(-9125 1975);
PAINT MONO (-9125 1975);
DISPLAY INVISIBLE (-9125 1975);
FORCEPROP 1 LAST HDL_POWER GND
J 1
(-9100 1900);
DISPLAY 0.872340 (-9100 1900);
PAINT GREEN (-9100 1900);
DISPLAY INVISIBLE (-9100 1900);
FORCEPROP 1 LAST PATH I126
J 0
(-9050 1975);
DISPLAY 0.872340 (-9050 1975);
PAINT AQUA (-9050 1975);
DISPLAY INVISIBLE (-9050 1975);
FORCEADD Q_CAP..1
(-9975 2350);
FORCEPROP 1 LAST LOCATION C2158
J 0
(-9925 2450);
DISPLAY 0.489362 (-9925 2450);
PAINT SKYBLUE (-9925 2450);
FORCEPROP 2 LAST $SEC 1
J 0
(-9925 2550);
DISPLAY 0.680851 (-9925 2550);
PAINT MONO (-9925 2550);
DISPLAY INVISIBLE (-9925 2550);
FORCEPROP 2 LAST CDS_SEC 1
J 0
(-9925 2550);
DISPLAY 1.021277 (-9925 2550);
DISPLAY INVISIBLE (-9925 2550);
FORCEPROP 1 LASTPIN (-9975 2450) $PN 1
J 0
(-9965 2430);
DISPLAY 0.489362 (-9965 2430);
FORCEPROP 1 LASTPIN (-9975 2250) $PN 2
J 0
(-9965 2230);
DISPLAY 0.489362 (-9965 2230);
FORCEPROP 1 LAST MATERIAL X6S
J 0
(-9925 2250);
DISPLAY 0.489362 (-9925 2250);
PAINT SKYBLUE (-9925 2250);
FORCEPROP 1 LAST TOLERANCE 20%
J 0
(-9925 2300);
DISPLAY 0.489362 (-9925 2300);
PAINT SKYBLUE (-9925 2300);
FORCEPROP 1 LAST VALUE 22UF
J 0
(-9925 2400);
DISPLAY 0.489362 (-9925 2400);
PAINT SKYBLUE (-9925 2400);
FORCEPROP 1 LAST VOLTAGE 4V
J 0
(-9925 2350);
DISPLAY 0.489362 (-9925 2350);
PAINT SKYBLUE (-9925 2350);
FORCEPROP 1 LAST PACK_TYPE C0402
J 0
(-9925 2150);
DISPLAY 0.489362 (-9925 2150);
PAINT SKYBLUE (-9925 2150);
FORCEPROP 2 LAST CDS_LIB pure_quanta
J 0
(-9975 2350);
PAINT MONO (-9975 2350);
DISPLAY INVISIBLE (-9975 2350);
FORCEPROP 1 LAST PATH I127
J 0
(-9925 2500);
DISPLAY 0.978723 (-9925 2500);
PAINT WHITE (-9925 2500);
DISPLAY INVISIBLE (-9925 2500);
FORCEPROP 1 LAST PART_NUMBER CH622KMEB02
J 0
(-9925 2200);
DISPLAY 0.489362 (-9925 2200);
PAINT SKYBLUE (-9925 2200);
DISPLAY INVISIBLE (-9925 2200);
FORCEADD Q_CAP..1
(-9525 2350);
FORCEPROP 1 LAST LOCATION C2160
J 0
(-9475 2450);
DISPLAY 0.489362 (-9475 2450);
PAINT SKYBLUE (-9475 2450);
FORCEPROP 2 LAST $SEC 1
J 0
(-9475 2550);
DISPLAY 0.680851 (-9475 2550);
PAINT MONO (-9475 2550);
DISPLAY INVISIBLE (-9475 2550);
FORCEPROP 2 LAST CDS_SEC 1
J 0
(-9475 2550);
DISPLAY 1.021277 (-9475 2550);
DISPLAY INVISIBLE (-9475 2550);
FORCEPROP 1 LASTPIN (-9525 2450) $PN 1
J 0
(-9515 2430);
DISPLAY 0.489362 (-9515 2430);
FORCEPROP 1 LASTPIN (-9525 2250) $PN 2
J 0
(-9515 2230);
DISPLAY 0.489362 (-9515 2230);
FORCEPROP 1 LAST MATERIAL X6S
J 0
(-9475 2250);
DISPLAY 0.489362 (-9475 2250);
PAINT SKYBLUE (-9475 2250);
FORCEPROP 1 LAST TOLERANCE 20%
J 0
(-9475 2300);
DISPLAY 0.489362 (-9475 2300);
PAINT SKYBLUE (-9475 2300);
FORCEPROP 1 LAST VALUE 22UF
J 0
(-9475 2400);
DISPLAY 0.489362 (-9475 2400);
PAINT SKYBLUE (-9475 2400);
FORCEPROP 1 LAST VOLTAGE 4V
J 0
(-9475 2350);
DISPLAY 0.489362 (-9475 2350);
PAINT SKYBLUE (-9475 2350);
FORCEPROP 1 LAST PACK_TYPE C0402
J 0
(-9475 2150);
DISPLAY 0.489362 (-9475 2150);
PAINT SKYBLUE (-9475 2150);
FORCEPROP 2 LAST CDS_LIB pure_quanta
J 0
(-9525 2350);
PAINT MONO (-9525 2350);
DISPLAY INVISIBLE (-9525 2350);
FORCEPROP 1 LAST PATH I128
J 0
(-9475 2500);
DISPLAY 0.978723 (-9475 2500);
PAINT WHITE (-9475 2500);
DISPLAY INVISIBLE (-9475 2500);
FORCEPROP 1 LAST PART_NUMBER CH622KMEB02
J 0
(-9475 2200);
DISPLAY 0.489362 (-9475 2200);
PAINT SKYBLUE (-9475 2200);
DISPLAY INVISIBLE (-9475 2200);
FORCEADD Q_CAP..1
(-9125 2350);
FORCEPROP 1 LAST LOCATION C2162
J 0
(-9075 2450);
DISPLAY 0.489362 (-9075 2450);
PAINT SKYBLUE (-9075 2450);
FORCEPROP 2 LAST $SEC 1
J 0
(-9075 2550);
DISPLAY 0.680851 (-9075 2550);
PAINT MONO (-9075 2550);
DISPLAY INVISIBLE (-9075 2550);
FORCEPROP 2 LAST CDS_SEC 1
J 0
(-9075 2550);
DISPLAY 1.021277 (-9075 2550);
DISPLAY INVISIBLE (-9075 2550);
FORCEPROP 1 LASTPIN (-9125 2450) $PN 1
J 0
(-9115 2430);
DISPLAY 0.489362 (-9115 2430);
FORCEPROP 1 LASTPIN (-9125 2250) $PN 2
J 0
(-9115 2230);
DISPLAY 0.489362 (-9115 2230);
FORCEPROP 1 LAST MATERIAL X6S
J 0
(-9075 2250);
DISPLAY 0.489362 (-9075 2250);
PAINT SKYBLUE (-9075 2250);
FORCEPROP 1 LAST TOLERANCE 20%
J 0
(-9075 2300);
DISPLAY 0.489362 (-9075 2300);
PAINT SKYBLUE (-9075 2300);
FORCEPROP 1 LAST VALUE 22UF
J 0
(-9075 2400);
DISPLAY 0.489362 (-9075 2400);
PAINT SKYBLUE (-9075 2400);
FORCEPROP 1 LAST VOLTAGE 4V
J 0
(-9075 2350);
DISPLAY 0.489362 (-9075 2350);
PAINT SKYBLUE (-9075 2350);
FORCEPROP 1 LAST PACK_TYPE C0402
J 0
(-9075 2150);
DISPLAY 0.489362 (-9075 2150);
PAINT SKYBLUE (-9075 2150);
FORCEPROP 2 LAST CDS_LIB pure_quanta
J 0
(-9125 2350);
PAINT MONO (-9125 2350);
DISPLAY INVISIBLE (-9125 2350);
FORCEPROP 1 LAST PATH I129
J 0
(-9075 2500);
DISPLAY 0.978723 (-9075 2500);
PAINT WHITE (-9075 2500);
DISPLAY INVISIBLE (-9075 2500);
FORCEPROP 1 LAST PART_NUMBER CH622KMEB02
J 0
(-9075 2200);
DISPLAY 0.489362 (-9075 2200);
PAINT SKYBLUE (-9075 2200);
DISPLAY INVISIBLE (-9075 2200);
FORCEADD UNIVERSAL_GND..1
(-7250 3850);
FORCEPROP 3 LASTPIN (-7250 3900) SIG_NAME GND\g
J 0
(-7240 3910);
DISPLAY 0.659574 (-7240 3910);
PAINT MONO (-7240 3910);
DISPLAY INVISIBLE (-7240 3910);
FORCEPROP 2 LAST CDS_LIB pure_quanta_power
J 0
(-7250 3850);
DISPLAY INVISIBLE (-7250 3850);
FORCEPROP 1 LAST HDL_POWER GND
J 1
(-7225 3775);
DISPLAY 0.872340 (-7225 3775);
PAINT GREEN (-7225 3775);
DISPLAY INVISIBLE (-7225 3775);
FORCEPROP 1 LAST PATH I130
J 0
(-7175 3850);
DISPLAY 0.872340 (-7175 3850);
PAINT AQUA (-7175 3850);
DISPLAY INVISIBLE (-7175 3850);
FORCEADD Q_CAP..1
(-8150 4200);
FORCEPROP 1 LAST LOCATION C2163
J 0
(-8100 4300);
DISPLAY 0.489362 (-8100 4300);
PAINT SKYBLUE (-8100 4300);
FORCEPROP 2 LAST $SEC 1
J 0
(-8100 4400);
DISPLAY 0.680851 (-8100 4400);
PAINT MONO (-8100 4400);
DISPLAY INVISIBLE (-8100 4400);
FORCEPROP 2 LAST CDS_SEC 1
J 0
(-8100 4400);
DISPLAY 1.021277 (-8100 4400);
DISPLAY INVISIBLE (-8100 4400);
FORCEPROP 1 LASTPIN (-8150 4300) $PN 1
J 0
(-8140 4280);
DISPLAY 0.489362 (-8140 4280);
FORCEPROP 1 LASTPIN (-8150 4100) $PN 2
J 0
(-8140 4080);
DISPLAY 0.489362 (-8140 4080);
FORCEPROP 1 LAST MATERIAL X6S
J 0
(-8100 4100);
DISPLAY 0.489362 (-8100 4100);
PAINT SKYBLUE (-8100 4100);
FORCEPROP 1 LAST TOLERANCE 20%
J 0
(-8100 4150);
DISPLAY 0.489362 (-8100 4150);
PAINT SKYBLUE (-8100 4150);
FORCEPROP 1 LAST VALUE 22UF
J 0
(-8100 4250);
DISPLAY 0.489362 (-8100 4250);
PAINT SKYBLUE (-8100 4250);
FORCEPROP 1 LAST VOLTAGE 4V
J 0
(-8100 4200);
DISPLAY 0.489362 (-8100 4200);
PAINT SKYBLUE (-8100 4200);
FORCEPROP 1 LAST PACK_TYPE C0402
J 0
(-8100 4000);
DISPLAY 0.489362 (-8100 4000);
PAINT SKYBLUE (-8100 4000);
FORCEPROP 2 LAST CDS_LIB pure_quanta
J 0
(-8150 4200);
PAINT MONO (-8150 4200);
DISPLAY INVISIBLE (-8150 4200);
FORCEPROP 1 LAST PATH I131
J 0
(-8100 4350);
DISPLAY 0.978723 (-8100 4350);
PAINT WHITE (-8100 4350);
DISPLAY INVISIBLE (-8100 4350);
FORCEPROP 1 LAST PART_NUMBER CH622KMEB02
J 0
(-8100 4050);
DISPLAY 0.489362 (-8100 4050);
PAINT SKYBLUE (-8100 4050);
DISPLAY INVISIBLE (-8100 4050);
FORCEADD UNIVERSAL_POWER..1
(-8150 4475);
FORCEPROP 3 LASTPIN (-8150 4425) SIG_NAME PVDD18_S5_P0\g
J 0
(-8140 4435);
DISPLAY 0.659574 (-8140 4435);
PAINT MONO (-8140 4435);
DISPLAY INVISIBLE (-8140 4435);
FORCEPROP 1 LAST HDL_POWER PVDD18_S5_P0
J 1
(-8150 4525);
DISPLAY 0.489362 (-8150 4525);
PAINT GREEN (-8150 4525);
FORCEPROP 2 LAST CDS_LIB pure_quanta_power
J 0
(-8150 4475);
DISPLAY INVISIBLE (-8150 4475);
FORCEPROP 1 LAST PATH I132
J 0
(-8100 4500);
DISPLAY 0.872340 (-8100 4500);
PAINT AQUA (-8100 4500);
DISPLAY INVISIBLE (-8100 4500);
FORCEADD Q_CAP..1
(-7700 4200);
FORCEPROP 1 LAST LOCATION C2164
J 0
(-7650 4300);
DISPLAY 0.489362 (-7650 4300);
PAINT SKYBLUE (-7650 4300);
FORCEPROP 2 LAST $SEC 1
J 0
(-7650 4400);
DISPLAY 0.680851 (-7650 4400);
PAINT MONO (-7650 4400);
DISPLAY INVISIBLE (-7650 4400);
FORCEPROP 2 LAST CDS_SEC 1
J 0
(-7650 4400);
DISPLAY 1.021277 (-7650 4400);
DISPLAY INVISIBLE (-7650 4400);
FORCEPROP 1 LASTPIN (-7700 4300) $PN 1
J 0
(-7690 4280);
DISPLAY 0.489362 (-7690 4280);
FORCEPROP 1 LASTPIN (-7700 4100) $PN 2
J 0
(-7690 4080);
DISPLAY 0.489362 (-7690 4080);
FORCEPROP 1 LAST MATERIAL X6S
J 0
(-7650 4100);
DISPLAY 0.489362 (-7650 4100);
PAINT SKYBLUE (-7650 4100);
FORCEPROP 1 LAST TOLERANCE 20%
J 0
(-7650 4150);
DISPLAY 0.489362 (-7650 4150);
PAINT SKYBLUE (-7650 4150);
FORCEPROP 1 LAST VALUE 22UF
J 0
(-7650 4250);
DISPLAY 0.489362 (-7650 4250);
PAINT SKYBLUE (-7650 4250);
FORCEPROP 1 LAST VOLTAGE 4V
J 0
(-7650 4200);
DISPLAY 0.489362 (-7650 4200);
PAINT SKYBLUE (-7650 4200);
FORCEPROP 1 LAST PACK_TYPE C0402
J 0
(-7650 4000);
DISPLAY 0.489362 (-7650 4000);
PAINT SKYBLUE (-7650 4000);
FORCEPROP 2 LAST CDS_LIB pure_quanta
J 0
(-7700 4200);
PAINT MONO (-7700 4200);
DISPLAY INVISIBLE (-7700 4200);
FORCEPROP 1 LAST PATH I133
J 0
(-7650 4350);
DISPLAY 0.978723 (-7650 4350);
PAINT WHITE (-7650 4350);
DISPLAY INVISIBLE (-7650 4350);
FORCEPROP 1 LAST PART_NUMBER CH622KMEB02
J 0
(-7650 4050);
DISPLAY 0.489362 (-7650 4050);
PAINT SKYBLUE (-7650 4050);
DISPLAY INVISIBLE (-7650 4050);
FORCEADD Q_CAP..1
(-7250 4200);
FORCEPROP 1 LAST LOCATION C3897
J 0
(-7200 4300);
DISPLAY 0.489362 (-7200 4300);
PAINT SKYBLUE (-7200 4300);
FORCEPROP 2 LAST $SEC 1
J 0
(-7200 4400);
DISPLAY 0.680851 (-7200 4400);
PAINT MONO (-7200 4400);
DISPLAY INVISIBLE (-7200 4400);
FORCEPROP 2 LAST CDS_SEC 1
J 0
(-7200 4400);
DISPLAY 1.021277 (-7200 4400);
DISPLAY INVISIBLE (-7200 4400);
FORCEPROP 1 LASTPIN (-7250 4300) $PN 1
J 0
(-7240 4280);
DISPLAY 0.489362 (-7240 4280);
FORCEPROP 1 LASTPIN (-7250 4100) $PN 2
J 0
(-7240 4080);
DISPLAY 0.489362 (-7240 4080);
FORCEPROP 1 LAST MATERIAL X6S
J 0
(-7200 4100);
DISPLAY 0.489362 (-7200 4100);
PAINT SKYBLUE (-7200 4100);
FORCEPROP 1 LAST TOLERANCE 20%
J 0
(-7200 4150);
DISPLAY 0.489362 (-7200 4150);
PAINT SKYBLUE (-7200 4150);
FORCEPROP 1 LAST VALUE 22UF
J 0
(-7200 4250);
DISPLAY 0.489362 (-7200 4250);
PAINT SKYBLUE (-7200 4250);
FORCEPROP 1 LAST VOLTAGE 4V
J 0
(-7200 4200);
DISPLAY 0.489362 (-7200 4200);
PAINT SKYBLUE (-7200 4200);
FORCEPROP 1 LAST PACK_TYPE C0402
J 0
(-7200 4000);
DISPLAY 0.489362 (-7200 4000);
PAINT SKYBLUE (-7200 4000);
FORCEPROP 2 LAST CDS_LIB pure_quanta
J 0
(-7250 4200);
PAINT MONO (-7250 4200);
DISPLAY INVISIBLE (-7250 4200);
FORCEPROP 1 LAST PATH I134
J 0
(-7200 4350);
DISPLAY 0.978723 (-7200 4350);
PAINT WHITE (-7200 4350);
DISPLAY INVISIBLE (-7200 4350);
FORCEPROP 1 LAST PART_NUMBER CH622KMEB02
J 0
(-7200 4050);
DISPLAY 0.489362 (-7200 4050);
PAINT SKYBLUE (-7200 4050);
DISPLAY INVISIBLE (-7200 4050);
FORCEADD Q_CAP..1
(-8200 5950);
FORCEPROP 1 LAST LOCATION C2131
J 0
(-8150 6050);
DISPLAY 0.489362 (-8150 6050);
PAINT SKYBLUE (-8150 6050);
FORCEPROP 2 LAST $SEC 1
J 0
(-8150 6150);
DISPLAY 0.680851 (-8150 6150);
PAINT MONO (-8150 6150);
DISPLAY INVISIBLE (-8150 6150);
FORCEPROP 2 LAST CDS_SEC 1
J 0
(-8150 6150);
DISPLAY 1.021277 (-8150 6150);
DISPLAY INVISIBLE (-8150 6150);
FORCEPROP 1 LASTPIN (-8200 6050) $PN 1
J 0
(-8190 6030);
DISPLAY 0.489362 (-8190 6030);
FORCEPROP 1 LASTPIN (-8200 5850) $PN 2
J 0
(-8190 5830);
DISPLAY 0.489362 (-8190 5830);
FORCEPROP 1 LAST MATERIAL X6S
J 0
(-8150 5850);
DISPLAY 0.489362 (-8150 5850);
PAINT SKYBLUE (-8150 5850);
FORCEPROP 1 LAST TOLERANCE 20%
J 0
(-8150 5900);
DISPLAY 0.489362 (-8150 5900);
PAINT SKYBLUE (-8150 5900);
FORCEPROP 1 LAST VALUE 22UF
J 0
(-8150 6000);
DISPLAY 0.489362 (-8150 6000);
PAINT SKYBLUE (-8150 6000);
FORCEPROP 1 LAST VOLTAGE 4V
J 0
(-8150 5950);
DISPLAY 0.489362 (-8150 5950);
PAINT SKYBLUE (-8150 5950);
FORCEPROP 1 LAST PACK_TYPE C0402
J 0
(-8150 5750);
DISPLAY 0.489362 (-8150 5750);
PAINT SKYBLUE (-8150 5750);
FORCEPROP 2 LAST CDS_LIB pure_quanta
J 0
(-8200 5950);
PAINT MONO (-8200 5950);
DISPLAY INVISIBLE (-8200 5950);
FORCEPROP 1 LAST PATH I135
J 0
(-8150 6100);
DISPLAY 0.978723 (-8150 6100);
PAINT WHITE (-8150 6100);
DISPLAY INVISIBLE (-8150 6100);
FORCEPROP 1 LAST PART_NUMBER CH622KMEB02
J 0
(-8150 5800);
DISPLAY 0.489362 (-8150 5800);
PAINT SKYBLUE (-8150 5800);
DISPLAY INVISIBLE (-8150 5800);
FORCEADD Q_CAP..1
(-7750 5950);
FORCEPROP 1 LAST LOCATION C2136
J 0
(-7700 6050);
DISPLAY 0.489362 (-7700 6050);
PAINT SKYBLUE (-7700 6050);
FORCEPROP 2 LAST $SEC 1
J 0
(-7700 6150);
DISPLAY 0.680851 (-7700 6150);
PAINT MONO (-7700 6150);
DISPLAY INVISIBLE (-7700 6150);
FORCEPROP 2 LAST CDS_SEC 1
J 0
(-7700 6150);
DISPLAY 1.021277 (-7700 6150);
DISPLAY INVISIBLE (-7700 6150);
FORCEPROP 1 LASTPIN (-7750 6050) $PN 1
J 0
(-7740 6030);
DISPLAY 0.489362 (-7740 6030);
FORCEPROP 1 LASTPIN (-7750 5850) $PN 2
J 0
(-7740 5830);
DISPLAY 0.489362 (-7740 5830);
FORCEPROP 1 LAST MATERIAL X6S
J 0
(-7700 5850);
DISPLAY 0.489362 (-7700 5850);
PAINT SKYBLUE (-7700 5850);
FORCEPROP 1 LAST TOLERANCE 20%
J 0
(-7700 5900);
DISPLAY 0.489362 (-7700 5900);
PAINT SKYBLUE (-7700 5900);
FORCEPROP 1 LAST VALUE 22UF
J 0
(-7700 6000);
DISPLAY 0.489362 (-7700 6000);
PAINT SKYBLUE (-7700 6000);
FORCEPROP 1 LAST VOLTAGE 4V
J 0
(-7700 5950);
DISPLAY 0.489362 (-7700 5950);
PAINT SKYBLUE (-7700 5950);
FORCEPROP 1 LAST PACK_TYPE C0402
J 0
(-7700 5750);
DISPLAY 0.489362 (-7700 5750);
PAINT SKYBLUE (-7700 5750);
FORCEPROP 2 LAST CDS_LIB pure_quanta
J 0
(-7750 5950);
PAINT MONO (-7750 5950);
DISPLAY INVISIBLE (-7750 5950);
FORCEPROP 1 LAST PATH I136
J 0
(-7700 6100);
DISPLAY 0.978723 (-7700 6100);
PAINT WHITE (-7700 6100);
DISPLAY INVISIBLE (-7700 6100);
FORCEPROP 1 LAST PART_NUMBER CH622KMEB02
J 0
(-7700 5800);
DISPLAY 0.489362 (-7700 5800);
PAINT SKYBLUE (-7700 5800);
DISPLAY INVISIBLE (-7700 5800);
FORCEADD Q_CAP..1
(-7300 5950);
FORCEPROP 1 LAST LOCATION C2141
J 0
(-7250 6050);
DISPLAY 0.489362 (-7250 6050);
PAINT SKYBLUE (-7250 6050);
FORCEPROP 2 LAST $SEC 1
J 0
(-7250 6150);
DISPLAY 0.680851 (-7250 6150);
PAINT MONO (-7250 6150);
DISPLAY INVISIBLE (-7250 6150);
FORCEPROP 2 LAST CDS_SEC 1
J 0
(-7250 6150);
DISPLAY 1.021277 (-7250 6150);
DISPLAY INVISIBLE (-7250 6150);
FORCEPROP 1 LASTPIN (-7300 6050) $PN 1
J 0
(-7290 6030);
DISPLAY 0.489362 (-7290 6030);
FORCEPROP 1 LASTPIN (-7300 5850) $PN 2
J 0
(-7290 5830);
DISPLAY 0.489362 (-7290 5830);
FORCEPROP 1 LAST MATERIAL X6S
J 0
(-7250 5850);
DISPLAY 0.489362 (-7250 5850);
PAINT SKYBLUE (-7250 5850);
FORCEPROP 1 LAST TOLERANCE 20%
J 0
(-7250 5900);
DISPLAY 0.489362 (-7250 5900);
PAINT SKYBLUE (-7250 5900);
FORCEPROP 1 LAST VALUE 22UF
J 0
(-7250 6000);
DISPLAY 0.489362 (-7250 6000);
PAINT SKYBLUE (-7250 6000);
FORCEPROP 1 LAST VOLTAGE 4V
J 0
(-7250 5950);
DISPLAY 0.489362 (-7250 5950);
PAINT SKYBLUE (-7250 5950);
FORCEPROP 1 LAST PACK_TYPE C0402
J 0
(-7250 5750);
DISPLAY 0.489362 (-7250 5750);
PAINT SKYBLUE (-7250 5750);
FORCEPROP 2 LAST CDS_LIB pure_quanta
J 0
(-7300 5950);
PAINT MONO (-7300 5950);
DISPLAY INVISIBLE (-7300 5950);
FORCEPROP 1 LAST PATH I137
J 0
(-7250 6100);
DISPLAY 0.978723 (-7250 6100);
PAINT WHITE (-7250 6100);
DISPLAY INVISIBLE (-7250 6100);
FORCEPROP 1 LAST PART_NUMBER CH622KMEB02
J 0
(-7250 5800);
DISPLAY 0.489362 (-7250 5800);
PAINT SKYBLUE (-7250 5800);
DISPLAY INVISIBLE (-7250 5800);
FORCEADD Q_CAP..1
(-6850 5950);
FORCEPROP 1 LAST LOCATION C2145
J 0
(-6800 6050);
DISPLAY 0.489362 (-6800 6050);
PAINT SKYBLUE (-6800 6050);
FORCEPROP 2 LAST $SEC 1
J 0
(-6800 6150);
DISPLAY 0.680851 (-6800 6150);
PAINT MONO (-6800 6150);
DISPLAY INVISIBLE (-6800 6150);
FORCEPROP 2 LAST CDS_SEC 1
J 0
(-6800 6150);
DISPLAY 1.021277 (-6800 6150);
DISPLAY INVISIBLE (-6800 6150);
FORCEPROP 1 LASTPIN (-6850 6050) $PN 1
J 0
(-6840 6030);
DISPLAY 0.489362 (-6840 6030);
FORCEPROP 1 LASTPIN (-6850 5850) $PN 2
J 0
(-6840 5830);
DISPLAY 0.489362 (-6840 5830);
FORCEPROP 1 LAST MATERIAL X6S
J 0
(-6800 5850);
DISPLAY 0.489362 (-6800 5850);
PAINT SKYBLUE (-6800 5850);
FORCEPROP 1 LAST TOLERANCE 20%
J 0
(-6800 5900);
DISPLAY 0.489362 (-6800 5900);
PAINT SKYBLUE (-6800 5900);
FORCEPROP 1 LAST VALUE 22UF
J 0
(-6800 6000);
DISPLAY 0.489362 (-6800 6000);
PAINT SKYBLUE (-6800 6000);
FORCEPROP 1 LAST VOLTAGE 4V
J 0
(-6800 5950);
DISPLAY 0.489362 (-6800 5950);
PAINT SKYBLUE (-6800 5950);
FORCEPROP 1 LAST PACK_TYPE C0402
J 0
(-6800 5750);
DISPLAY 0.489362 (-6800 5750);
PAINT SKYBLUE (-6800 5750);
FORCEPROP 2 LAST CDS_LIB pure_quanta
J 0
(-6850 5950);
PAINT MONO (-6850 5950);
DISPLAY INVISIBLE (-6850 5950);
FORCEPROP 1 LAST PATH I138
J 0
(-6800 6100);
DISPLAY 0.978723 (-6800 6100);
PAINT WHITE (-6800 6100);
DISPLAY INVISIBLE (-6800 6100);
FORCEPROP 1 LAST PART_NUMBER CH622KMEB02
J 0
(-6800 5800);
DISPLAY 0.489362 (-6800 5800);
PAINT SKYBLUE (-6800 5800);
DISPLAY INVISIBLE (-6800 5800);
FORCEADD Q_CAP..1
(-6400 5950);
FORCEPROP 1 LAST LOCATION C2149
J 0
(-6350 6050);
DISPLAY 0.489362 (-6350 6050);
PAINT SKYBLUE (-6350 6050);
FORCEPROP 2 LAST $SEC 1
J 0
(-6350 6150);
DISPLAY 0.680851 (-6350 6150);
PAINT MONO (-6350 6150);
DISPLAY INVISIBLE (-6350 6150);
FORCEPROP 2 LAST CDS_SEC 1
J 0
(-6350 6150);
DISPLAY 1.021277 (-6350 6150);
DISPLAY INVISIBLE (-6350 6150);
FORCEPROP 1 LASTPIN (-6400 6050) $PN 1
J 0
(-6390 6030);
DISPLAY 0.489362 (-6390 6030);
FORCEPROP 1 LASTPIN (-6400 5850) $PN 2
J 0
(-6390 5830);
DISPLAY 0.489362 (-6390 5830);
FORCEPROP 1 LAST MATERIAL X6S
J 0
(-6350 5850);
DISPLAY 0.489362 (-6350 5850);
PAINT SKYBLUE (-6350 5850);
FORCEPROP 1 LAST TOLERANCE 20%
J 0
(-6350 5900);
DISPLAY 0.489362 (-6350 5900);
PAINT SKYBLUE (-6350 5900);
FORCEPROP 1 LAST VALUE 22UF
J 0
(-6350 6000);
DISPLAY 0.489362 (-6350 6000);
PAINT SKYBLUE (-6350 6000);
FORCEPROP 1 LAST VOLTAGE 4V
J 0
(-6350 5950);
DISPLAY 0.489362 (-6350 5950);
PAINT SKYBLUE (-6350 5950);
FORCEPROP 1 LAST PACK_TYPE C0402
J 0
(-6350 5750);
DISPLAY 0.489362 (-6350 5750);
PAINT SKYBLUE (-6350 5750);
FORCEPROP 2 LAST CDS_LIB pure_quanta
J 0
(-6400 5950);
PAINT MONO (-6400 5950);
DISPLAY INVISIBLE (-6400 5950);
FORCEPROP 1 LAST PATH I139
J 0
(-6350 6100);
DISPLAY 0.978723 (-6350 6100);
PAINT WHITE (-6350 6100);
DISPLAY INVISIBLE (-6350 6100);
FORCEPROP 1 LAST PART_NUMBER CH622KMEB02
J 0
(-6350 5800);
DISPLAY 0.489362 (-6350 5800);
PAINT SKYBLUE (-6350 5800);
DISPLAY INVISIBLE (-6350 5800);
FORCEADD UNIVERSAL_POWER..1
(-8200 6225);
FORCEPROP 3 LASTPIN (-8200 6175) SIG_NAME PVDDIO_P0\g
J 0
(-8190 6185);
DISPLAY 0.659574 (-8190 6185);
PAINT MONO (-8190 6185);
DISPLAY INVISIBLE (-8190 6185);
FORCEPROP 1 LAST HDL_POWER PVDDIO_P0
J 1
(-8200 6275);
DISPLAY 0.489362 (-8200 6275);
PAINT GREEN (-8200 6275);
FORCEPROP 2 LAST CDS_LIB pure_quanta_power
J 0
(-8200 6225);
DISPLAY INVISIBLE (-8200 6225);
FORCEPROP 1 LAST PATH I140
J 0
(-8150 6250);
DISPLAY 0.872340 (-8150 6250);
PAINT AQUA (-8150 6250);
DISPLAY INVISIBLE (-8150 6250);
FORCEADD Q_CAP..1
(-5950 5950);
FORCEPROP 1 LAST LOCATION C3898
J 0
(-5900 6050);
DISPLAY 0.489362 (-5900 6050);
PAINT SKYBLUE (-5900 6050);
FORCEPROP 2 LAST $SEC 1
J 0
(-5900 6150);
DISPLAY 0.680851 (-5900 6150);
PAINT MONO (-5900 6150);
DISPLAY INVISIBLE (-5900 6150);
FORCEPROP 2 LAST CDS_SEC 1
J 0
(-5900 6150);
DISPLAY 1.021277 (-5900 6150);
DISPLAY INVISIBLE (-5900 6150);
FORCEPROP 1 LASTPIN (-5950 6050) $PN 1
J 0
(-5940 6030);
DISPLAY 0.489362 (-5940 6030);
FORCEPROP 1 LASTPIN (-5950 5850) $PN 2
J 0
(-5940 5830);
DISPLAY 0.489362 (-5940 5830);
FORCEPROP 1 LAST MATERIAL X6S
J 0
(-5900 5850);
DISPLAY 0.489362 (-5900 5850);
PAINT SKYBLUE (-5900 5850);
FORCEPROP 1 LAST TOLERANCE 20%
J 0
(-5900 5900);
DISPLAY 0.489362 (-5900 5900);
PAINT SKYBLUE (-5900 5900);
FORCEPROP 1 LAST VALUE 22UF
J 0
(-5900 6000);
DISPLAY 0.489362 (-5900 6000);
PAINT SKYBLUE (-5900 6000);
FORCEPROP 1 LAST VOLTAGE 4V
J 0
(-5900 5950);
DISPLAY 0.489362 (-5900 5950);
PAINT SKYBLUE (-5900 5950);
FORCEPROP 1 LAST PACK_TYPE C0402
J 0
(-5900 5750);
DISPLAY 0.489362 (-5900 5750);
PAINT SKYBLUE (-5900 5750);
FORCEPROP 2 LAST CDS_LIB pure_quanta
J 0
(-5950 5950);
PAINT MONO (-5950 5950);
DISPLAY INVISIBLE (-5950 5950);
FORCEPROP 1 LAST PATH I141
J 0
(-5900 6100);
DISPLAY 0.978723 (-5900 6100);
PAINT WHITE (-5900 6100);
DISPLAY INVISIBLE (-5900 6100);
FORCEPROP 1 LAST PART_NUMBER CH622KMEB02
J 0
(-5900 5800);
DISPLAY 0.489362 (-5900 5800);
PAINT SKYBLUE (-5900 5800);
DISPLAY INVISIBLE (-5900 5800);
FORCEADD UNIVERSAL_GND..1
(-5500 5600);
FORCEPROP 3 LASTPIN (-5500 5650) SIG_NAME GND\g
J 0
(-5490 5660);
DISPLAY 0.659574 (-5490 5660);
PAINT MONO (-5490 5660);
DISPLAY INVISIBLE (-5490 5660);
FORCEPROP 2 LAST CDS_LIB pure_quanta_power
J 0
(-5500 5600);
PAINT MONO (-5500 5600);
DISPLAY INVISIBLE (-5500 5600);
FORCEPROP 1 LAST HDL_POWER GND
J 1
(-5475 5525);
DISPLAY 0.872340 (-5475 5525);
PAINT GREEN (-5475 5525);
DISPLAY INVISIBLE (-5475 5525);
FORCEPROP 1 LAST PATH I142
J 0
(-5425 5600);
DISPLAY 0.872340 (-5425 5600);
PAINT AQUA (-5425 5600);
DISPLAY INVISIBLE (-5425 5600);
FORCEADD Q_CAP..1
(-5500 5950);
FORCEPROP 1 LAST LOCATION C3899
J 0
(-5450 6050);
DISPLAY 0.489362 (-5450 6050);
PAINT SKYBLUE (-5450 6050);
FORCEPROP 2 LAST $SEC 1
J 0
(-5450 6150);
DISPLAY 0.680851 (-5450 6150);
PAINT MONO (-5450 6150);
DISPLAY INVISIBLE (-5450 6150);
FORCEPROP 2 LAST CDS_SEC 1
J 0
(-5450 6150);
DISPLAY 1.021277 (-5450 6150);
DISPLAY INVISIBLE (-5450 6150);
FORCEPROP 1 LASTPIN (-5500 6050) $PN 1
J 0
(-5490 6030);
DISPLAY 0.489362 (-5490 6030);
FORCEPROP 1 LASTPIN (-5500 5850) $PN 2
J 0
(-5490 5830);
DISPLAY 0.489362 (-5490 5830);
FORCEPROP 1 LAST MATERIAL X6S
J 0
(-5450 5850);
DISPLAY 0.489362 (-5450 5850);
PAINT SKYBLUE (-5450 5850);
FORCEPROP 1 LAST TOLERANCE 20%
J 0
(-5450 5900);
DISPLAY 0.489362 (-5450 5900);
PAINT SKYBLUE (-5450 5900);
FORCEPROP 1 LAST VALUE 22UF
J 0
(-5450 6000);
DISPLAY 0.489362 (-5450 6000);
PAINT SKYBLUE (-5450 6000);
FORCEPROP 1 LAST VOLTAGE 4V
J 0
(-5450 5950);
DISPLAY 0.489362 (-5450 5950);
PAINT SKYBLUE (-5450 5950);
FORCEPROP 1 LAST PACK_TYPE C0402
J 0
(-5450 5750);
DISPLAY 0.489362 (-5450 5750);
PAINT SKYBLUE (-5450 5750);
FORCEPROP 2 LAST CDS_LIB pure_quanta
J 0
(-5500 5950);
PAINT MONO (-5500 5950);
DISPLAY INVISIBLE (-5500 5950);
FORCEPROP 1 LAST PATH I143
J 0
(-5450 6100);
DISPLAY 0.978723 (-5450 6100);
PAINT WHITE (-5450 6100);
DISPLAY INVISIBLE (-5450 6100);
FORCEPROP 1 LAST PART_NUMBER CH622KMEB02
J 0
(-5450 5800);
DISPLAY 0.489362 (-5450 5800);
PAINT SKYBLUE (-5450 5800);
DISPLAY INVISIBLE (-5450 5800);
FORCEADD UNIVERSAL_GND..1
(-12700 3900);
FORCEPROP 3 LASTPIN (-12700 3950) SIG_NAME GND\g
J 0
(-12690 3960);
DISPLAY 0.659574 (-12690 3960);
PAINT MONO (-12690 3960);
DISPLAY INVISIBLE (-12690 3960);
FORCEPROP 2 LAST CDS_LIB pure_quanta_power
J 0
(-12700 3900);
PAINT MONO (-12700 3900);
DISPLAY INVISIBLE (-12700 3900);
FORCEPROP 1 LAST HDL_POWER GND
J 1
(-12675 3825);
DISPLAY 0.872340 (-12675 3825);
PAINT GREEN (-12675 3825);
DISPLAY INVISIBLE (-12675 3825);
FORCEPROP 1 LAST PATH I82
J 0
(-12625 3900);
DISPLAY 0.872340 (-12625 3900);
PAINT AQUA (-12625 3900);
DISPLAY INVISIBLE (-12625 3900);
FORCEADD Q_CAP..1
(-13100 4275);
FORCEPROP 1 LAST LOCATION C3888
J 0
(-13050 4375);
DISPLAY 0.489362 (-13050 4375);
PAINT SKYBLUE (-13050 4375);
FORCEPROP 2 LAST $SEC 1
J 0
(-13050 4475);
DISPLAY 0.680851 (-13050 4475);
PAINT MONO (-13050 4475);
DISPLAY INVISIBLE (-13050 4475);
FORCEPROP 2 LAST CDS_SEC 1
J 0
(-13050 4475);
DISPLAY 1.021277 (-13050 4475);
DISPLAY INVISIBLE (-13050 4475);
FORCEPROP 1 LASTPIN (-13100 4375) $PN 1
J 0
(-13090 4355);
DISPLAY 0.489362 (-13090 4355);
FORCEPROP 1 LASTPIN (-13100 4175) $PN 2
J 0
(-13090 4155);
DISPLAY 0.489362 (-13090 4155);
FORCEPROP 1 LAST MATERIAL X6S
J 0
(-13050 4175);
DISPLAY 0.489362 (-13050 4175);
PAINT SKYBLUE (-13050 4175);
FORCEPROP 1 LAST TOLERANCE 20%
J 0
(-13050 4225);
DISPLAY 0.489362 (-13050 4225);
PAINT SKYBLUE (-13050 4225);
FORCEPROP 1 LAST VALUE 22UF
J 0
(-13050 4325);
DISPLAY 0.489362 (-13050 4325);
PAINT SKYBLUE (-13050 4325);
FORCEPROP 1 LAST VOLTAGE 4V
J 0
(-13050 4275);
DISPLAY 0.489362 (-13050 4275);
PAINT SKYBLUE (-13050 4275);
FORCEPROP 1 LAST PACK_TYPE C0402
J 0
(-13050 4075);
DISPLAY 0.489362 (-13050 4075);
PAINT SKYBLUE (-13050 4075);
FORCEPROP 2 LAST CDS_LIB pure_quanta
J 0
(-13100 4275);
PAINT MONO (-13100 4275);
DISPLAY INVISIBLE (-13100 4275);
FORCEPROP 1 LAST PATH I83
J 0
(-13050 4425);
DISPLAY 0.978723 (-13050 4425);
PAINT WHITE (-13050 4425);
DISPLAY INVISIBLE (-13050 4425);
FORCEPROP 1 LAST PART_NUMBER CH622KMEB02
J 0
(-13050 4125);
DISPLAY 0.489362 (-13050 4125);
PAINT SKYBLUE (-13050 4125);
DISPLAY INVISIBLE (-13050 4125);
FORCEADD UNIVERSAL_POWER..1
(-13100 4550);
FORCEPROP 3 LASTPIN (-13100 4500) SIG_NAME PVDDCR_SOC_P0\g
J 0
(-13090 4510);
DISPLAY 0.659574 (-13090 4510);
PAINT MONO (-13090 4510);
DISPLAY INVISIBLE (-13090 4510);
FORCEPROP 1 LAST HDL_POWER PVDDCR_SOC_P0
J 1
(-13100 4600);
DISPLAY 0.489362 (-13100 4600);
PAINT GREEN (-13100 4600);
FORCEPROP 2 LAST CDS_LIB pure_quanta_power
J 0
(-13100 4550);
DISPLAY INVISIBLE (-13100 4550);
FORCEPROP 1 LAST PATH I84
J 0
(-13050 4575);
DISPLAY 0.872340 (-13050 4575);
PAINT AQUA (-13050 4575);
DISPLAY INVISIBLE (-13050 4575);
FORCEADD Q_CAP..1
(-13125 5050);
FORCEPROP 1 LAST LOCATION C2130
J 0
(-13075 5150);
DISPLAY 0.489362 (-13075 5150);
PAINT SKYBLUE (-13075 5150);
FORCEPROP 2 LAST $SEC 1
J 0
(-13075 5250);
DISPLAY 0.680851 (-13075 5250);
PAINT MONO (-13075 5250);
DISPLAY INVISIBLE (-13075 5250);
FORCEPROP 2 LAST CDS_SEC 1
J 0
(-13075 5250);
DISPLAY 1.021277 (-13075 5250);
DISPLAY INVISIBLE (-13075 5250);
FORCEPROP 1 LASTPIN (-13125 5150) $PN 1
J 0
(-13115 5130);
DISPLAY 0.489362 (-13115 5130);
FORCEPROP 1 LASTPIN (-13125 4950) $PN 2
J 0
(-13115 4930);
DISPLAY 0.489362 (-13115 4930);
FORCEPROP 1 LAST MATERIAL X6S
J 0
(-13075 4950);
DISPLAY 0.489362 (-13075 4950);
PAINT SKYBLUE (-13075 4950);
FORCEPROP 1 LAST TOLERANCE 20%
J 0
(-13075 5000);
DISPLAY 0.489362 (-13075 5000);
PAINT SKYBLUE (-13075 5000);
FORCEPROP 1 LAST VALUE 22UF
J 0
(-13075 5100);
DISPLAY 0.489362 (-13075 5100);
PAINT SKYBLUE (-13075 5100);
FORCEPROP 1 LAST VOLTAGE 4V
J 0
(-13075 5050);
DISPLAY 0.489362 (-13075 5050);
PAINT SKYBLUE (-13075 5050);
FORCEPROP 1 LAST PACK_TYPE C0402
J 0
(-13075 4850);
DISPLAY 0.489362 (-13075 4850);
PAINT SKYBLUE (-13075 4850);
FORCEPROP 2 LAST CDS_LIB pure_quanta
J 0
(-13125 5050);
PAINT MONO (-13125 5050);
DISPLAY INVISIBLE (-13125 5050);
FORCEPROP 1 LAST PATH I85
J 0
(-13075 5200);
DISPLAY 0.978723 (-13075 5200);
PAINT WHITE (-13075 5200);
DISPLAY INVISIBLE (-13075 5200);
FORCEPROP 1 LAST PART_NUMBER CH622KMEB02
J 0
(-13075 4900);
DISPLAY 0.489362 (-13075 4900);
PAINT SKYBLUE (-13075 4900);
DISPLAY INVISIBLE (-13075 4900);
FORCEADD Q_CAP..1
(-12700 4275);
FORCEPROP 1 LAST LOCATION C3889
J 0
(-12650 4375);
DISPLAY 0.489362 (-12650 4375);
PAINT SKYBLUE (-12650 4375);
FORCEPROP 2 LAST $SEC 1
J 0
(-12650 4475);
DISPLAY 0.680851 (-12650 4475);
PAINT MONO (-12650 4475);
DISPLAY INVISIBLE (-12650 4475);
FORCEPROP 2 LAST CDS_SEC 1
J 0
(-12650 4475);
DISPLAY 1.021277 (-12650 4475);
DISPLAY INVISIBLE (-12650 4475);
FORCEPROP 1 LASTPIN (-12700 4375) $PN 1
J 0
(-12690 4355);
DISPLAY 0.489362 (-12690 4355);
FORCEPROP 1 LASTPIN (-12700 4175) $PN 2
J 0
(-12690 4155);
DISPLAY 0.489362 (-12690 4155);
FORCEPROP 1 LAST MATERIAL X6S
J 0
(-12650 4175);
DISPLAY 0.489362 (-12650 4175);
PAINT SKYBLUE (-12650 4175);
FORCEPROP 1 LAST TOLERANCE 20%
J 0
(-12650 4225);
DISPLAY 0.489362 (-12650 4225);
PAINT SKYBLUE (-12650 4225);
FORCEPROP 1 LAST VALUE 22UF
J 0
(-12650 4325);
DISPLAY 0.489362 (-12650 4325);
PAINT SKYBLUE (-12650 4325);
FORCEPROP 1 LAST VOLTAGE 4V
J 0
(-12650 4275);
DISPLAY 0.489362 (-12650 4275);
PAINT SKYBLUE (-12650 4275);
FORCEPROP 1 LAST PACK_TYPE C0402
J 0
(-12650 4075);
DISPLAY 0.489362 (-12650 4075);
PAINT SKYBLUE (-12650 4075);
FORCEPROP 2 LAST CDS_LIB pure_quanta
J 0
(-12700 4275);
PAINT MONO (-12700 4275);
DISPLAY INVISIBLE (-12700 4275);
FORCEPROP 1 LAST PATH I86
J 0
(-12650 4425);
DISPLAY 0.978723 (-12650 4425);
PAINT WHITE (-12650 4425);
DISPLAY INVISIBLE (-12650 4425);
FORCEPROP 1 LAST PART_NUMBER CH622KMEB02
J 0
(-12650 4125);
DISPLAY 0.489362 (-12650 4125);
PAINT SKYBLUE (-12650 4125);
DISPLAY INVISIBLE (-12650 4125);
FORCEADD Q_CAP..1
(-12675 5050);
FORCEPROP 1 LAST LOCATION C2135
J 0
(-12625 5150);
DISPLAY 0.489362 (-12625 5150);
PAINT SKYBLUE (-12625 5150);
FORCEPROP 2 LAST $SEC 1
J 0
(-12625 5250);
DISPLAY 0.680851 (-12625 5250);
PAINT MONO (-12625 5250);
DISPLAY INVISIBLE (-12625 5250);
FORCEPROP 2 LAST CDS_SEC 1
J 0
(-12625 5250);
DISPLAY 1.021277 (-12625 5250);
DISPLAY INVISIBLE (-12625 5250);
FORCEPROP 1 LASTPIN (-12675 5150) $PN 1
J 0
(-12665 5130);
DISPLAY 0.489362 (-12665 5130);
FORCEPROP 1 LASTPIN (-12675 4950) $PN 2
J 0
(-12665 4930);
DISPLAY 0.489362 (-12665 4930);
FORCEPROP 1 LAST MATERIAL X6S
J 0
(-12625 4950);
DISPLAY 0.489362 (-12625 4950);
PAINT SKYBLUE (-12625 4950);
FORCEPROP 1 LAST TOLERANCE 20%
J 0
(-12625 5000);
DISPLAY 0.489362 (-12625 5000);
PAINT SKYBLUE (-12625 5000);
FORCEPROP 1 LAST VALUE 22UF
J 0
(-12625 5100);
DISPLAY 0.489362 (-12625 5100);
PAINT SKYBLUE (-12625 5100);
FORCEPROP 1 LAST VOLTAGE 4V
J 0
(-12625 5050);
DISPLAY 0.489362 (-12625 5050);
PAINT SKYBLUE (-12625 5050);
FORCEPROP 1 LAST PACK_TYPE C0402
J 0
(-12625 4850);
DISPLAY 0.489362 (-12625 4850);
PAINT SKYBLUE (-12625 4850);
FORCEPROP 2 LAST CDS_LIB pure_quanta
J 0
(-12675 5050);
PAINT MONO (-12675 5050);
DISPLAY INVISIBLE (-12675 5050);
FORCEPROP 1 LAST PATH I87
J 0
(-12625 5200);
DISPLAY 0.978723 (-12625 5200);
PAINT WHITE (-12625 5200);
DISPLAY INVISIBLE (-12625 5200);
FORCEPROP 1 LAST PART_NUMBER CH622KMEB02
J 0
(-12625 4900);
DISPLAY 0.489362 (-12625 4900);
PAINT SKYBLUE (-12625 4900);
DISPLAY INVISIBLE (-12625 4900);
FORCEADD UNIVERSAL_POWER..1
(-13125 5325);
FORCEPROP 3 LASTPIN (-13125 5275) SIG_NAME PVDDCR_SOC_P0\g
J 0
(-13115 5285);
DISPLAY 0.659574 (-13115 5285);
PAINT MONO (-13115 5285);
DISPLAY INVISIBLE (-13115 5285);
FORCEPROP 1 LAST HDL_POWER PVDDCR_SOC_P0
J 1
(-13125 5375);
DISPLAY 0.489362 (-13125 5375);
PAINT GREEN (-13125 5375);
FORCEPROP 2 LAST CDS_LIB pure_quanta_power
J 0
(-13125 5325);
DISPLAY INVISIBLE (-13125 5325);
FORCEPROP 1 LAST PATH I88
J 0
(-13075 5350);
DISPLAY 0.872340 (-13075 5350);
PAINT AQUA (-13075 5350);
DISPLAY INVISIBLE (-13075 5350);
FORCEADD Q_CAP..1
(-13125 5850);
FORCEPROP 1 LAST LOCATION C2129
J 0
(-13075 5950);
DISPLAY 0.489362 (-13075 5950);
PAINT SKYBLUE (-13075 5950);
FORCEPROP 2 LAST $SEC 1
J 0
(-13075 6050);
DISPLAY 0.680851 (-13075 6050);
PAINT MONO (-13075 6050);
DISPLAY INVISIBLE (-13075 6050);
FORCEPROP 2 LAST CDS_SEC 1
J 0
(-13075 6050);
DISPLAY 1.021277 (-13075 6050);
DISPLAY INVISIBLE (-13075 6050);
FORCEPROP 1 LASTPIN (-13125 5950) $PN 1
J 0
(-13115 5930);
DISPLAY 0.489362 (-13115 5930);
FORCEPROP 1 LASTPIN (-13125 5750) $PN 2
J 0
(-13115 5730);
DISPLAY 0.489362 (-13115 5730);
FORCEPROP 1 LAST MATERIAL X6S
J 0
(-13075 5750);
DISPLAY 0.489362 (-13075 5750);
PAINT SKYBLUE (-13075 5750);
FORCEPROP 1 LAST TOLERANCE 20%
J 0
(-13075 5800);
DISPLAY 0.489362 (-13075 5800);
PAINT SKYBLUE (-13075 5800);
FORCEPROP 1 LAST VALUE 22UF
J 0
(-13075 5900);
DISPLAY 0.489362 (-13075 5900);
PAINT SKYBLUE (-13075 5900);
FORCEPROP 1 LAST VOLTAGE 4V
J 0
(-13075 5850);
DISPLAY 0.489362 (-13075 5850);
PAINT SKYBLUE (-13075 5850);
FORCEPROP 1 LAST PACK_TYPE C0402
J 0
(-13075 5650);
DISPLAY 0.489362 (-13075 5650);
PAINT SKYBLUE (-13075 5650);
FORCEPROP 2 LAST CDS_LIB pure_quanta
J 0
(-13125 5850);
PAINT MONO (-13125 5850);
DISPLAY INVISIBLE (-13125 5850);
FORCEPROP 1 LAST PATH I89
J 0
(-13075 6000);
DISPLAY 0.978723 (-13075 6000);
PAINT WHITE (-13075 6000);
DISPLAY INVISIBLE (-13075 6000);
FORCEPROP 1 LAST PART_NUMBER CH622KMEB02
J 0
(-13075 5700);
DISPLAY 0.489362 (-13075 5700);
PAINT SKYBLUE (-13075 5700);
DISPLAY INVISIBLE (-13075 5700);
FORCEADD Q_CAP..1
(-12675 5850);
FORCEPROP 1 LAST LOCATION C2134
J 0
(-12625 5950);
DISPLAY 0.489362 (-12625 5950);
PAINT SKYBLUE (-12625 5950);
FORCEPROP 2 LAST $SEC 1
J 0
(-12625 6050);
DISPLAY 0.680851 (-12625 6050);
PAINT MONO (-12625 6050);
DISPLAY INVISIBLE (-12625 6050);
FORCEPROP 2 LAST CDS_SEC 1
J 0
(-12625 6050);
DISPLAY 1.021277 (-12625 6050);
DISPLAY INVISIBLE (-12625 6050);
FORCEPROP 1 LASTPIN (-12675 5950) $PN 1
J 0
(-12665 5930);
DISPLAY 0.489362 (-12665 5930);
FORCEPROP 1 LASTPIN (-12675 5750) $PN 2
J 0
(-12665 5730);
DISPLAY 0.489362 (-12665 5730);
FORCEPROP 1 LAST MATERIAL X6S
J 0
(-12625 5750);
DISPLAY 0.489362 (-12625 5750);
PAINT SKYBLUE (-12625 5750);
FORCEPROP 1 LAST TOLERANCE 20%
J 0
(-12625 5800);
DISPLAY 0.489362 (-12625 5800);
PAINT SKYBLUE (-12625 5800);
FORCEPROP 1 LAST VALUE 22UF
J 0
(-12625 5900);
DISPLAY 0.489362 (-12625 5900);
PAINT SKYBLUE (-12625 5900);
FORCEPROP 1 LAST VOLTAGE 4V
J 0
(-12625 5850);
DISPLAY 0.489362 (-12625 5850);
PAINT SKYBLUE (-12625 5850);
FORCEPROP 1 LAST PACK_TYPE C0402
J 0
(-12625 5650);
DISPLAY 0.489362 (-12625 5650);
PAINT SKYBLUE (-12625 5650);
FORCEPROP 2 LAST CDS_LIB pure_quanta
J 0
(-12675 5850);
PAINT MONO (-12675 5850);
DISPLAY INVISIBLE (-12675 5850);
FORCEPROP 1 LAST PATH I90
J 0
(-12625 6000);
DISPLAY 0.978723 (-12625 6000);
PAINT WHITE (-12625 6000);
DISPLAY INVISIBLE (-12625 6000);
FORCEPROP 1 LAST PART_NUMBER CH622KMEB02
J 0
(-12625 5700);
DISPLAY 0.489362 (-12625 5700);
PAINT SKYBLUE (-12625 5700);
DISPLAY INVISIBLE (-12625 5700);
FORCEADD UNIVERSAL_POWER..1
(-13125 6125);
FORCEPROP 3 LASTPIN (-13125 6075) SIG_NAME PVDDCR_SOC_P0\g
J 0
(-13115 6085);
DISPLAY 0.659574 (-13115 6085);
PAINT MONO (-13115 6085);
DISPLAY INVISIBLE (-13115 6085);
FORCEPROP 1 LAST HDL_POWER PVDDCR_SOC_P0
J 1
(-13125 6175);
DISPLAY 0.489362 (-13125 6175);
PAINT GREEN (-13125 6175);
FORCEPROP 2 LAST CDS_LIB pure_quanta_power
J 0
(-13125 6125);
DISPLAY INVISIBLE (-13125 6125);
FORCEPROP 1 LAST PATH I91
J 0
(-13075 6150);
DISPLAY 0.872340 (-13075 6150);
PAINT AQUA (-13075 6150);
DISPLAY INVISIBLE (-13075 6150);
FORCEADD Q_CAP..1
(-12225 5050);
FORCEPROP 1 LAST LOCATION C2140
J 0
(-12175 5150);
DISPLAY 0.489362 (-12175 5150);
PAINT SKYBLUE (-12175 5150);
FORCEPROP 2 LAST $SEC 1
J 0
(-12175 5250);
DISPLAY 0.680851 (-12175 5250);
PAINT MONO (-12175 5250);
DISPLAY INVISIBLE (-12175 5250);
FORCEPROP 2 LAST CDS_SEC 1
J 0
(-12175 5250);
DISPLAY 1.021277 (-12175 5250);
DISPLAY INVISIBLE (-12175 5250);
FORCEPROP 1 LASTPIN (-12225 5150) $PN 1
J 0
(-12215 5130);
DISPLAY 0.489362 (-12215 5130);
FORCEPROP 1 LASTPIN (-12225 4950) $PN 2
J 0
(-12215 4930);
DISPLAY 0.489362 (-12215 4930);
FORCEPROP 1 LAST MATERIAL X6S
J 0
(-12175 4950);
DISPLAY 0.489362 (-12175 4950);
PAINT SKYBLUE (-12175 4950);
FORCEPROP 1 LAST TOLERANCE 20%
J 0
(-12175 5000);
DISPLAY 0.489362 (-12175 5000);
PAINT SKYBLUE (-12175 5000);
FORCEPROP 1 LAST VALUE 22UF
J 0
(-12175 5100);
DISPLAY 0.489362 (-12175 5100);
PAINT SKYBLUE (-12175 5100);
FORCEPROP 1 LAST VOLTAGE 4V
J 0
(-12175 5050);
DISPLAY 0.489362 (-12175 5050);
PAINT SKYBLUE (-12175 5050);
FORCEPROP 1 LAST PACK_TYPE C0402
J 0
(-12175 4850);
DISPLAY 0.489362 (-12175 4850);
PAINT SKYBLUE (-12175 4850);
FORCEPROP 2 LAST CDS_LIB pure_quanta
J 0
(-12225 5050);
PAINT MONO (-12225 5050);
DISPLAY INVISIBLE (-12225 5050);
FORCEPROP 1 LAST PATH I92
J 0
(-12175 5200);
DISPLAY 0.978723 (-12175 5200);
PAINT WHITE (-12175 5200);
DISPLAY INVISIBLE (-12175 5200);
FORCEPROP 1 LAST PART_NUMBER CH622KMEB02
J 0
(-12175 4900);
DISPLAY 0.489362 (-12175 4900);
PAINT SKYBLUE (-12175 4900);
DISPLAY INVISIBLE (-12175 4900);
FORCEADD Q_CAP..1
(-11775 5050);
FORCEPROP 1 LAST LOCATION C2144
J 0
(-11725 5150);
DISPLAY 0.489362 (-11725 5150);
PAINT SKYBLUE (-11725 5150);
FORCEPROP 2 LAST $SEC 1
J 0
(-11725 5250);
DISPLAY 0.680851 (-11725 5250);
PAINT MONO (-11725 5250);
DISPLAY INVISIBLE (-11725 5250);
FORCEPROP 2 LAST CDS_SEC 1
J 0
(-11725 5250);
DISPLAY 1.021277 (-11725 5250);
DISPLAY INVISIBLE (-11725 5250);
FORCEPROP 1 LASTPIN (-11775 5150) $PN 1
J 0
(-11765 5130);
DISPLAY 0.489362 (-11765 5130);
FORCEPROP 1 LASTPIN (-11775 4950) $PN 2
J 0
(-11765 4930);
DISPLAY 0.489362 (-11765 4930);
FORCEPROP 1 LAST MATERIAL X6S
J 0
(-11725 4950);
DISPLAY 0.489362 (-11725 4950);
PAINT SKYBLUE (-11725 4950);
FORCEPROP 1 LAST TOLERANCE 20%
J 0
(-11725 5000);
DISPLAY 0.489362 (-11725 5000);
PAINT SKYBLUE (-11725 5000);
FORCEPROP 1 LAST VALUE 22UF
J 0
(-11725 5100);
DISPLAY 0.489362 (-11725 5100);
PAINT SKYBLUE (-11725 5100);
FORCEPROP 1 LAST VOLTAGE 4V
J 0
(-11725 5050);
DISPLAY 0.489362 (-11725 5050);
PAINT SKYBLUE (-11725 5050);
FORCEPROP 1 LAST PACK_TYPE C0402
J 0
(-11725 4850);
DISPLAY 0.489362 (-11725 4850);
PAINT SKYBLUE (-11725 4850);
FORCEPROP 2 LAST CDS_LIB pure_quanta
J 0
(-11775 5050);
PAINT MONO (-11775 5050);
DISPLAY INVISIBLE (-11775 5050);
FORCEPROP 1 LAST PATH I93
J 0
(-11725 5200);
DISPLAY 0.978723 (-11725 5200);
PAINT WHITE (-11725 5200);
DISPLAY INVISIBLE (-11725 5200);
FORCEPROP 1 LAST PART_NUMBER CH622KMEB02
J 0
(-11725 4900);
DISPLAY 0.489362 (-11725 4900);
PAINT SKYBLUE (-11725 4900);
DISPLAY INVISIBLE (-11725 4900);
FORCEADD Q_CAP..1
(-11325 5050);
FORCEPROP 1 LAST LOCATION C2148
J 0
(-11275 5150);
DISPLAY 0.489362 (-11275 5150);
PAINT SKYBLUE (-11275 5150);
FORCEPROP 2 LAST $SEC 1
J 0
(-11275 5250);
DISPLAY 0.680851 (-11275 5250);
PAINT MONO (-11275 5250);
DISPLAY INVISIBLE (-11275 5250);
FORCEPROP 2 LAST CDS_SEC 1
J 0
(-11275 5250);
DISPLAY 1.021277 (-11275 5250);
DISPLAY INVISIBLE (-11275 5250);
FORCEPROP 1 LASTPIN (-11325 5150) $PN 1
J 0
(-11315 5130);
DISPLAY 0.489362 (-11315 5130);
FORCEPROP 1 LASTPIN (-11325 4950) $PN 2
J 0
(-11315 4930);
DISPLAY 0.489362 (-11315 4930);
FORCEPROP 1 LAST MATERIAL X6S
J 0
(-11275 4950);
DISPLAY 0.489362 (-11275 4950);
PAINT SKYBLUE (-11275 4950);
FORCEPROP 1 LAST TOLERANCE 20%
J 0
(-11275 5000);
DISPLAY 0.489362 (-11275 5000);
PAINT SKYBLUE (-11275 5000);
FORCEPROP 1 LAST VALUE 22UF
J 0
(-11275 5100);
DISPLAY 0.489362 (-11275 5100);
PAINT SKYBLUE (-11275 5100);
FORCEPROP 1 LAST VOLTAGE 4V
J 0
(-11275 5050);
DISPLAY 0.489362 (-11275 5050);
PAINT SKYBLUE (-11275 5050);
FORCEPROP 1 LAST PACK_TYPE C0402
J 0
(-11275 4850);
DISPLAY 0.489362 (-11275 4850);
PAINT SKYBLUE (-11275 4850);
FORCEPROP 2 LAST CDS_LIB pure_quanta
J 0
(-11325 5050);
PAINT MONO (-11325 5050);
DISPLAY INVISIBLE (-11325 5050);
FORCEPROP 1 LAST PATH I94
J 0
(-11275 5200);
DISPLAY 0.978723 (-11275 5200);
PAINT WHITE (-11275 5200);
DISPLAY INVISIBLE (-11275 5200);
FORCEPROP 1 LAST PART_NUMBER CH622KMEB02
J 0
(-11275 4900);
DISPLAY 0.489362 (-11275 4900);
PAINT SKYBLUE (-11275 4900);
DISPLAY INVISIBLE (-11275 4900);
FORCEADD Q_CAP..1
(-12225 5850);
FORCEPROP 1 LAST LOCATION C2139
J 0
(-12175 5950);
DISPLAY 0.489362 (-12175 5950);
PAINT SKYBLUE (-12175 5950);
FORCEPROP 2 LAST $SEC 1
J 0
(-12175 6050);
DISPLAY 0.680851 (-12175 6050);
PAINT MONO (-12175 6050);
DISPLAY INVISIBLE (-12175 6050);
FORCEPROP 2 LAST CDS_SEC 1
J 0
(-12175 6050);
DISPLAY 1.021277 (-12175 6050);
DISPLAY INVISIBLE (-12175 6050);
FORCEPROP 1 LASTPIN (-12225 5950) $PN 1
J 0
(-12215 5930);
DISPLAY 0.489362 (-12215 5930);
FORCEPROP 1 LASTPIN (-12225 5750) $PN 2
J 0
(-12215 5730);
DISPLAY 0.489362 (-12215 5730);
FORCEPROP 1 LAST MATERIAL X6S
J 0
(-12175 5750);
DISPLAY 0.489362 (-12175 5750);
PAINT SKYBLUE (-12175 5750);
FORCEPROP 1 LAST TOLERANCE 20%
J 0
(-12175 5800);
DISPLAY 0.489362 (-12175 5800);
PAINT SKYBLUE (-12175 5800);
FORCEPROP 1 LAST VALUE 22UF
J 0
(-12175 5900);
DISPLAY 0.489362 (-12175 5900);
PAINT SKYBLUE (-12175 5900);
FORCEPROP 1 LAST VOLTAGE 4V
J 0
(-12175 5850);
DISPLAY 0.489362 (-12175 5850);
PAINT SKYBLUE (-12175 5850);
FORCEPROP 1 LAST PACK_TYPE C0402
J 0
(-12175 5650);
DISPLAY 0.489362 (-12175 5650);
PAINT SKYBLUE (-12175 5650);
FORCEPROP 2 LAST CDS_LIB pure_quanta
J 0
(-12225 5850);
PAINT MONO (-12225 5850);
DISPLAY INVISIBLE (-12225 5850);
FORCEPROP 1 LAST PATH I95
J 0
(-12175 6000);
DISPLAY 0.978723 (-12175 6000);
PAINT WHITE (-12175 6000);
DISPLAY INVISIBLE (-12175 6000);
FORCEPROP 1 LAST PART_NUMBER CH622KMEB02
J 0
(-12175 5700);
DISPLAY 0.489362 (-12175 5700);
PAINT SKYBLUE (-12175 5700);
DISPLAY INVISIBLE (-12175 5700);
FORCEADD Q_CAP..1
(-11775 5850);
FORCEPROP 1 LAST LOCATION C2143
J 0
(-11725 5950);
DISPLAY 0.489362 (-11725 5950);
PAINT SKYBLUE (-11725 5950);
FORCEPROP 2 LAST $SEC 1
J 0
(-11725 6050);
DISPLAY 0.680851 (-11725 6050);
PAINT MONO (-11725 6050);
DISPLAY INVISIBLE (-11725 6050);
FORCEPROP 2 LAST CDS_SEC 1
J 0
(-11725 6050);
DISPLAY 1.021277 (-11725 6050);
DISPLAY INVISIBLE (-11725 6050);
FORCEPROP 1 LASTPIN (-11775 5950) $PN 1
J 0
(-11765 5930);
DISPLAY 0.489362 (-11765 5930);
FORCEPROP 1 LASTPIN (-11775 5750) $PN 2
J 0
(-11765 5730);
DISPLAY 0.489362 (-11765 5730);
FORCEPROP 1 LAST MATERIAL X6S
J 0
(-11725 5750);
DISPLAY 0.489362 (-11725 5750);
PAINT SKYBLUE (-11725 5750);
FORCEPROP 1 LAST TOLERANCE 20%
J 0
(-11725 5800);
DISPLAY 0.489362 (-11725 5800);
PAINT SKYBLUE (-11725 5800);
FORCEPROP 1 LAST VALUE 22UF
J 0
(-11725 5900);
DISPLAY 0.489362 (-11725 5900);
PAINT SKYBLUE (-11725 5900);
FORCEPROP 1 LAST VOLTAGE 4V
J 0
(-11725 5850);
DISPLAY 0.489362 (-11725 5850);
PAINT SKYBLUE (-11725 5850);
FORCEPROP 1 LAST PACK_TYPE C0402
J 0
(-11725 5650);
DISPLAY 0.489362 (-11725 5650);
PAINT SKYBLUE (-11725 5650);
FORCEPROP 2 LAST CDS_LIB pure_quanta
J 0
(-11775 5850);
PAINT MONO (-11775 5850);
DISPLAY INVISIBLE (-11775 5850);
FORCEPROP 1 LAST PATH I96
J 0
(-11725 6000);
DISPLAY 0.978723 (-11725 6000);
PAINT WHITE (-11725 6000);
DISPLAY INVISIBLE (-11725 6000);
FORCEPROP 1 LAST PART_NUMBER CH622KMEB02
J 0
(-11725 5700);
DISPLAY 0.489362 (-11725 5700);
PAINT SKYBLUE (-11725 5700);
DISPLAY INVISIBLE (-11725 5700);
FORCEADD Q_CAP..1
(-10875 5050);
FORCEPROP 1 LAST LOCATION C2152
J 0
(-10825 5150);
DISPLAY 0.489362 (-10825 5150);
PAINT SKYBLUE (-10825 5150);
FORCEPROP 2 LAST $SEC 1
J 0
(-10825 5250);
DISPLAY 0.680851 (-10825 5250);
PAINT MONO (-10825 5250);
DISPLAY INVISIBLE (-10825 5250);
FORCEPROP 2 LAST CDS_SEC 1
J 0
(-10825 5250);
DISPLAY 1.021277 (-10825 5250);
DISPLAY INVISIBLE (-10825 5250);
FORCEPROP 1 LASTPIN (-10875 5150) $PN 1
J 0
(-10865 5130);
DISPLAY 0.489362 (-10865 5130);
FORCEPROP 1 LASTPIN (-10875 4950) $PN 2
J 0
(-10865 4930);
DISPLAY 0.489362 (-10865 4930);
FORCEPROP 1 LAST MATERIAL X6S
J 0
(-10825 4950);
DISPLAY 0.489362 (-10825 4950);
PAINT SKYBLUE (-10825 4950);
FORCEPROP 1 LAST TOLERANCE 20%
J 0
(-10825 5000);
DISPLAY 0.489362 (-10825 5000);
PAINT SKYBLUE (-10825 5000);
FORCEPROP 1 LAST VALUE 22UF
J 0
(-10825 5100);
DISPLAY 0.489362 (-10825 5100);
PAINT SKYBLUE (-10825 5100);
FORCEPROP 1 LAST VOLTAGE 4V
J 0
(-10825 5050);
DISPLAY 0.489362 (-10825 5050);
PAINT SKYBLUE (-10825 5050);
FORCEPROP 1 LAST PACK_TYPE C0402
J 0
(-10825 4850);
DISPLAY 0.489362 (-10825 4850);
PAINT SKYBLUE (-10825 4850);
FORCEPROP 2 LAST CDS_LIB pure_quanta
J 0
(-10875 5050);
PAINT MONO (-10875 5050);
DISPLAY INVISIBLE (-10875 5050);
FORCEPROP 1 LAST PATH I97
J 0
(-10825 5200);
DISPLAY 0.978723 (-10825 5200);
PAINT WHITE (-10825 5200);
DISPLAY INVISIBLE (-10825 5200);
FORCEPROP 1 LAST PART_NUMBER CH622KMEB02
J 0
(-10825 4900);
DISPLAY 0.489362 (-10825 4900);
PAINT SKYBLUE (-10825 4900);
DISPLAY INVISIBLE (-10825 4900);
FORCEADD Q_CAP..1
(-10425 5050);
FORCEPROP 1 LAST LOCATION C2155
J 0
(-10375 5150);
DISPLAY 0.489362 (-10375 5150);
PAINT SKYBLUE (-10375 5150);
FORCEPROP 2 LAST $SEC 1
J 0
(-10375 5250);
DISPLAY 0.680851 (-10375 5250);
PAINT MONO (-10375 5250);
DISPLAY INVISIBLE (-10375 5250);
FORCEPROP 2 LAST CDS_SEC 1
J 0
(-10375 5250);
DISPLAY 1.021277 (-10375 5250);
DISPLAY INVISIBLE (-10375 5250);
FORCEPROP 1 LASTPIN (-10425 5150) $PN 1
J 0
(-10415 5130);
DISPLAY 0.489362 (-10415 5130);
FORCEPROP 1 LASTPIN (-10425 4950) $PN 2
J 0
(-10415 4930);
DISPLAY 0.489362 (-10415 4930);
FORCEPROP 1 LAST MATERIAL X6S
J 0
(-10375 4950);
DISPLAY 0.489362 (-10375 4950);
PAINT SKYBLUE (-10375 4950);
FORCEPROP 1 LAST TOLERANCE 20%
J 0
(-10375 5000);
DISPLAY 0.489362 (-10375 5000);
PAINT SKYBLUE (-10375 5000);
FORCEPROP 1 LAST VALUE 22UF
J 0
(-10375 5100);
DISPLAY 0.489362 (-10375 5100);
PAINT SKYBLUE (-10375 5100);
FORCEPROP 1 LAST VOLTAGE 4V
J 0
(-10375 5050);
DISPLAY 0.489362 (-10375 5050);
PAINT SKYBLUE (-10375 5050);
FORCEPROP 1 LAST PACK_TYPE C0402
J 0
(-10375 4850);
DISPLAY 0.489362 (-10375 4850);
PAINT SKYBLUE (-10375 4850);
FORCEPROP 2 LAST CDS_LIB pure_quanta
J 0
(-10425 5050);
PAINT MONO (-10425 5050);
DISPLAY INVISIBLE (-10425 5050);
FORCEPROP 1 LAST PATH I98
J 0
(-10375 5200);
DISPLAY 0.978723 (-10375 5200);
PAINT WHITE (-10375 5200);
DISPLAY INVISIBLE (-10375 5200);
FORCEPROP 1 LAST PART_NUMBER CH622KMEB02
J 0
(-10375 4900);
DISPLAY 0.489362 (-10375 4900);
PAINT SKYBLUE (-10375 4900);
DISPLAY INVISIBLE (-10375 4900);
FORCEADD Q_CAP..1
(-10875 5850);
FORCEPROP 1 LAST LOCATION C2151
J 0
(-10825 5950);
DISPLAY 0.489362 (-10825 5950);
PAINT SKYBLUE (-10825 5950);
FORCEPROP 2 LAST $SEC 1
J 0
(-10825 6050);
DISPLAY 0.680851 (-10825 6050);
PAINT MONO (-10825 6050);
DISPLAY INVISIBLE (-10825 6050);
FORCEPROP 2 LAST CDS_SEC 1
J 0
(-10825 6050);
DISPLAY 1.021277 (-10825 6050);
DISPLAY INVISIBLE (-10825 6050);
FORCEPROP 1 LASTPIN (-10875 5950) $PN 1
J 0
(-10865 5930);
DISPLAY 0.489362 (-10865 5930);
FORCEPROP 1 LASTPIN (-10875 5750) $PN 2
J 0
(-10865 5730);
DISPLAY 0.489362 (-10865 5730);
FORCEPROP 1 LAST MATERIAL X6S
J 0
(-10825 5750);
DISPLAY 0.489362 (-10825 5750);
PAINT SKYBLUE (-10825 5750);
FORCEPROP 1 LAST TOLERANCE 20%
J 0
(-10825 5800);
DISPLAY 0.489362 (-10825 5800);
PAINT SKYBLUE (-10825 5800);
FORCEPROP 1 LAST VALUE 22UF
J 0
(-10825 5900);
DISPLAY 0.489362 (-10825 5900);
PAINT SKYBLUE (-10825 5900);
FORCEPROP 1 LAST VOLTAGE 4V
J 0
(-10825 5850);
DISPLAY 0.489362 (-10825 5850);
PAINT SKYBLUE (-10825 5850);
FORCEPROP 1 LAST PACK_TYPE C0402
J 0
(-10825 5650);
DISPLAY 0.489362 (-10825 5650);
PAINT SKYBLUE (-10825 5650);
FORCEPROP 2 LAST CDS_LIB pure_quanta
J 0
(-10875 5850);
PAINT MONO (-10875 5850);
DISPLAY INVISIBLE (-10875 5850);
FORCEPROP 1 LAST PATH I99
J 0
(-10825 6000);
DISPLAY 0.978723 (-10825 6000);
PAINT WHITE (-10825 6000);
DISPLAY INVISIBLE (-10825 6000);
FORCEPROP 1 LAST PART_NUMBER CH622KMEB02
J 0
(-10825 5700);
DISPLAY 0.489362 (-10825 5700);
PAINT SKYBLUE (-10825 5700);
DISPLAY INVISIBLE (-10825 5700);
FORCEADD QUANTA_TITLE_BLOCK_C..1
(-4275 325);
FORCEPROP 0 LAST CDS_CON_LAST_MODIFIED Thu Sep 14 16:12:02 2023
J 0
(-6160 340);
DISPLAY INVISIBLE (-6160 340);
FORCEPROP 1 LAST CUSTOM_TXT_CDS <CON_LAST_MODIFIED>
J 0
(-6160 340);
DISPLAY 0.978723 (-6160 340);
FORCEPROP 2 LAST CUSTOM_TXT_CDS <XR_PAGE_TITLE>
J 0
(-12165 5575);
DISPLAY 0.638298 (-12165 5575);
PAINT PINK (-12165 5575);
DISPLAY INVISIBLE (-12165 5575);
FORCEPROP 1 LAST CUSTOM_TXT_CDS <NAME_2>
J 0
(-7450 375);
FORCEPROP 1 LAST CUSTOM_TXT_CDS <NAME_1>
J 0
(-7450 500);
FORCEPROP 1 LAST CUSTOM_TXT_CDS <Q_NUMBER>
J 0
(-5678 428);
DISPLAY 1.212766 (-5678 428);
FORCEPROP 1 LAST CUSTOM_TXT_CDS <Q_PROJ>
J 0
(-6657 427);
DISPLAY 1.212766 (-6657 427);
FORCEPROP 1 LAST CUSTOM_TXT_CDS <Q_REV>
J 0
(-4459 428);
DISPLAY 1.212766 (-4459 428);
FORCEPROP 1 LAST CUSTOM_TXT_CDS <CON_PAGE_NUM> OF <CON_TOTAL_PAGES>
J 0
(-4721 343);
DISPLAY 0.978723 (-4721 343);
FORCEPROP 1 LAST Q_TITLE CPU0 CAVITY TOP DECOUPLING CAPS
J 0
(-13550 400);
DISPLAY 2.446809 (-13550 400);
PAINT GREEN (-13550 400);
FORCEPROP 2 LAST PAGE_BORDER TRUE
J 0
(-12165 5575);
DISPLAY 0.638298 (-12165 5575);
PAINT PINK (-12165 5575);
DISPLAY INVISIBLE (-12165 5575);
FORCEPROP 1 LAST CDS_LMAN_SYM_OUTLINE -9475,6775,100,-125
J 0
(-4275 325);
DISPLAY 0.468085 (-4275 325);
PAINT GREEN (-4275 325);
DISPLAY INVISIBLE (-4275 325);
FORCEPROP 2 LAST CDS_LIB pure_quanta
J 0
(-4275 325);
DISPLAY INVISIBLE (-4275 325);
FORCEPROP 2 LAST CDS_XR_PAGE_TITLE CR-68 : @T6G_MB_LIB.T6G(SCH_1):PAGE68
J 0
(-12165 5575);
DISPLAY 0.638298 (-12165 5575);
PAINT PINK (-12165 5575);
DISPLAY INVISIBLE (-12165 5575);
FORCEPROP 1 LAST Q_DEPT BU9
J 1
(-8038 374);
DISPLAY 1.957447 (-8038 374);
PAINT GREEN (-8038 374);
DISPLAY INVISIBLE (-8038 374);
FORCEPROP 1 LAST COMMENT_BODY TRUE
J 0
(-4263 312);
DISPLAY 0.978723 (-4263 312);
PAINT GREEN (-4263 312);
DISPLAY INVISIBLE (-4263 312);
WIRE 16 -1 (-11775 1775)(-12225 1775);
WIRE 16 -1 (-11325 1775)(-11775 1775);
WIRE 16 -1 (-11775 1700)(-11775 1775);
WIRE 16 -1 (-12225 1700)(-12225 1775);
WIRE 16 -1 (-12225 1775)(-12675 1775);
WIRE 16 -1 (-12675 1700)(-12675 1775);
WIRE 16 -1 (-12675 1775)(-13125 1775);
WIRE 16 -1 (-10875 1775)(-11325 1775);
WIRE 16 -1 (-11325 1775)(-11325 1700);
WIRE 16 -1 (-10875 1700)(-10875 1775);
WIRE 16 -1 (-13125 1775)(-13125 1825);
WIRE 16 -1 (-13125 1775)(-13125 1700);
WIRE 16 -1 (-12225 1375)(-12675 1375);
WIRE 16 -1 (-11775 1375)(-12225 1375);
WIRE 16 -1 (-12225 1375)(-12225 1500);
WIRE 16 -1 (-12675 1375)(-12675 1500);
WIRE 16 -1 (-12675 1375)(-13125 1375);
WIRE 16 -1 (-13125 1375)(-13125 1500);
WIRE 16 -1 (-11325 1375)(-11775 1375);
WIRE 16 -1 (-11775 1375)(-11775 1500);
WIRE 16 -1 (-10875 1375)(-11325 1375);
WIRE 16 -1 (-11325 1375)(-11325 1500);
WIRE 16 -1 (-10875 1375)(-10875 1500);
WIRE 16 -1 (-10875 1275)(-10875 1375);
WIRE 16 -1 (-11775 2525)(-12225 2525);
WIRE 16 -1 (-11325 2525)(-11775 2525);
WIRE 16 -1 (-11775 2450)(-11775 2525);
WIRE 16 -1 (-12225 2525)(-12225 2450);
WIRE 16 -1 (-12225 2525)(-12675 2525);
WIRE 16 -1 (-12675 2450)(-12675 2525);
WIRE 16 -1 (-12675 2525)(-13125 2525);
WIRE 16 -1 (-10875 2525)(-11325 2525);
WIRE 16 -1 (-11325 2450)(-11325 2525);
WIRE 16 -1 (-10425 2525)(-10875 2525);
WIRE 16 -1 (-10875 2525)(-10875 2450);
WIRE 16 -1 (-13125 2525)(-13125 2575);
WIRE 16 -1 (-13125 2525)(-13125 2450);
WIRE 16 -1 (-9975 2525)(-10425 2525);
WIRE 16 -1 (-10425 2450)(-10425 2525);
WIRE 16 -1 (-9525 2525)(-9975 2525);
WIRE 16 -1 (-9975 2450)(-9975 2525);
WIRE 16 -1 (-9125 2525)(-9525 2525);
WIRE 16 -1 (-9525 2525)(-9525 2450);
WIRE 16 -1 (-9125 2450)(-9125 2525);
WIRE 16 -1 (-12225 2125)(-12675 2125);
WIRE 16 -1 (-11775 2125)(-12225 2125);
WIRE 16 -1 (-12225 2125)(-12225 2250);
WIRE 16 -1 (-12675 2125)(-12675 2250);
WIRE 16 -1 (-12675 2125)(-13125 2125);
WIRE 16 -1 (-13125 2125)(-13125 2250);
WIRE 16 -1 (-11325 2125)(-11775 2125);
WIRE 16 -1 (-11775 2125)(-11775 2250);
WIRE 16 -1 (-10875 2125)(-11325 2125);
WIRE 16 -1 (-11325 2125)(-11325 2250);
WIRE 16 -1 (-10425 2125)(-10875 2125);
WIRE 16 -1 (-10875 2125)(-10875 2250);
WIRE 16 -1 (-9975 2125)(-10425 2125);
WIRE 16 -1 (-10425 2125)(-10425 2250);
WIRE 16 -1 (-9525 2125)(-9975 2125);
WIRE 16 -1 (-9975 2125)(-9975 2250);
WIRE 16 -1 (-9125 2125)(-9525 2125);
WIRE 16 -1 (-9525 2125)(-9525 2250);
WIRE 16 -1 (-9125 2125)(-9125 2250);
WIRE 16 -1 (-9125 2025)(-9125 2125);
WIRE 16 -1 (-12700 4050)(-12700 4175);
WIRE 16 -1 (-12700 3950)(-12700 4050);
WIRE 16 -1 (-12700 4050)(-13100 4050);
WIRE 16 -1 (-13100 4050)(-13100 4175);
WIRE 16 -1 (-12225 4825)(-12675 4825);
WIRE 16 -1 (-11775 4825)(-12225 4825);
WIRE 16 -1 (-12225 4825)(-12225 4950);
WIRE 16 -1 (-12675 4825)(-12675 4950);
WIRE 16 -1 (-12675 4825)(-13125 4825);
WIRE 16 -1 (-13125 4825)(-13125 4950);
WIRE 16 -1 (-11325 4825)(-11775 4825);
WIRE 16 -1 (-11775 4825)(-11775 4950);
WIRE 16 -1 (-10875 4825)(-11325 4825);
WIRE 16 -1 (-11325 4825)(-11325 4950);
WIRE 16 -1 (-10425 4825)(-10875 4825);
WIRE 16 -1 (-10875 4825)(-10875 4950);
WIRE 16 -1 (-9975 4825)(-10425 4825);
WIRE 16 -1 (-10425 4825)(-10425 4950);
WIRE 16 -1 (-9525 4825)(-9975 4825);
WIRE 16 -1 (-9975 4825)(-9975 4950);
WIRE 16 -1 (-9125 4825)(-9525 4825);
WIRE 16 -1 (-9525 4825)(-9525 4950);
WIRE 16 -1 (-9125 4825)(-9125 4950);
WIRE 16 -1 (-9125 4725)(-9125 4825);
WIRE 16 -1 (-12700 4375)(-12700 4450);
WIRE 16 -1 (-12700 4450)(-13100 4450);
WIRE 16 -1 (-13100 4450)(-13100 4500);
WIRE 16 -1 (-13100 4450)(-13100 4375);
WIRE 16 -1 (-11775 6025)(-12225 6025);
WIRE 16 -1 (-11325 6025)(-11775 6025);
WIRE 16 -1 (-11775 5950)(-11775 6025);
WIRE 16 -1 (-12225 6025)(-12225 5950);
WIRE 16 -1 (-12225 6025)(-12675 6025);
WIRE 16 -1 (-12675 5950)(-12675 6025);
WIRE 16 -1 (-12675 6025)(-13125 6025);
WIRE 16 -1 (-10875 6025)(-11325 6025);
WIRE 16 -1 (-11325 5950)(-11325 6025);
WIRE 16 -1 (-10425 6025)(-10875 6025);
WIRE 16 -1 (-10875 6025)(-10875 5950);
WIRE 16 -1 (-13125 6025)(-13125 6075);
WIRE 16 -1 (-13125 6025)(-13125 5950);
WIRE 16 -1 (-9975 6025)(-10425 6025);
WIRE 16 -1 (-10425 5950)(-10425 6025);
WIRE 16 -1 (-9525 6025)(-9975 6025);
WIRE 16 -1 (-9975 5950)(-9975 6025);
WIRE 16 -1 (-9125 6025)(-9525 6025);
WIRE 16 -1 (-9525 6025)(-9525 5950);
WIRE 16 -1 (-9125 5950)(-9125 6025);
WIRE 16 -1 (-9125 5625)(-9125 5750);
WIRE 16 -1 (-9125 5525)(-9125 5625);
WIRE 16 -1 (-9125 5625)(-9525 5625);
WIRE 16 -1 (-9525 5625)(-9525 5750);
WIRE 16 -1 (-9525 5625)(-9975 5625);
WIRE 16 -1 (-9975 5625)(-9975 5750);
WIRE 16 -1 (-9975 5625)(-10425 5625);
WIRE 16 -1 (-10425 5625)(-10425 5750);
WIRE 16 -1 (-10425 5625)(-10875 5625);
WIRE 16 -1 (-10875 5625)(-10875 5750);
WIRE 16 -1 (-10875 5625)(-11325 5625);
WIRE 16 -1 (-11325 5625)(-11325 5750);
WIRE 16 -1 (-11325 5625)(-11775 5625);
WIRE 16 -1 (-11775 5625)(-11775 5750);
WIRE 16 -1 (-11775 5625)(-12225 5625);
WIRE 16 -1 (-12225 5625)(-12225 5750);
WIRE 16 -1 (-12225 5625)(-12675 5625);
WIRE 16 -1 (-12675 5625)(-12675 5750);
WIRE 16 -1 (-12675 5625)(-13125 5625);
WIRE 16 -1 (-13125 5625)(-13125 5750);
WIRE 16 -1 (-11775 5225)(-12225 5225);
WIRE 16 -1 (-11325 5225)(-11775 5225);
WIRE 16 -1 (-11775 5150)(-11775 5225);
WIRE 16 -1 (-12225 5225)(-12225 5150);
WIRE 16 -1 (-12225 5225)(-12675 5225);
WIRE 16 -1 (-12675 5150)(-12675 5225);
WIRE 16 -1 (-12675 5225)(-13125 5225);
WIRE 16 -1 (-10875 5225)(-11325 5225);
WIRE 16 -1 (-11325 5150)(-11325 5225);
WIRE 16 -1 (-10425 5225)(-10875 5225);
WIRE 16 -1 (-10875 5225)(-10875 5150);
WIRE 16 -1 (-13125 5225)(-13125 5275);
WIRE 16 -1 (-13125 5225)(-13125 5150);
WIRE 16 -1 (-9975 5225)(-10425 5225);
WIRE 16 -1 (-10425 5150)(-10425 5225);
WIRE 16 -1 (-9525 5225)(-9975 5225);
WIRE 16 -1 (-9975 5150)(-9975 5225);
WIRE 16 -1 (-9125 5225)(-9525 5225);
WIRE 16 -1 (-9525 5225)(-9525 5150);
WIRE 16 -1 (-9125 5150)(-9125 5225);
WIRE 16 3135 (-13400 3025)(-8725 3025);
WIRE 16 3135 (-13400 1150)(-13400 3025);
WIRE 16 3135 (-8725 1150)(-8725 3025);
WIRE 16 3135 (-13400 1150)(-8725 1150);
WIRE 16 3135 (-13400 6700)(-8725 6700);
WIRE 16 3135 (-13400 3675)(-13400 6700);
WIRE 16 3135 (-8725 3675)(-8725 6700);
WIRE 16 3135 (-13400 3675)(-8725 3675);
WIRE 16 -1 (-6850 6125)(-7300 6125);
WIRE 16 -1 (-6400 6125)(-6850 6125);
WIRE 16 -1 (-6850 6050)(-6850 6125);
WIRE 16 -1 (-7300 6125)(-7300 6050);
WIRE 16 -1 (-7300 6125)(-7750 6125);
WIRE 16 -1 (-7750 6050)(-7750 6125);
WIRE 16 -1 (-7750 6125)(-8200 6125);
WIRE 16 -1 (-5950 6125)(-6400 6125);
WIRE 16 -1 (-6400 6050)(-6400 6125);
WIRE 16 -1 (-5500 6125)(-5950 6125);
WIRE 16 -1 (-5950 6050)(-5950 6125);
WIRE 16 -1 (-8200 6125)(-8200 6175);
WIRE 16 -1 (-8200 6125)(-8200 6050);
WIRE 16 -1 (-5500 6050)(-5500 6125);
WIRE 16 -1 (-7300 5725)(-7750 5725);
WIRE 16 -1 (-6850 5725)(-7300 5725);
WIRE 16 -1 (-7300 5725)(-7300 5850);
WIRE 16 -1 (-7750 5725)(-7750 5850);
WIRE 16 -1 (-7750 5725)(-8200 5725);
WIRE 16 -1 (-8200 5725)(-8200 5850);
WIRE 16 -1 (-6400 5725)(-6850 5725);
WIRE 16 -1 (-6850 5725)(-6850 5850);
WIRE 16 -1 (-5950 5725)(-6400 5725);
WIRE 16 -1 (-6400 5725)(-6400 5850);
WIRE 16 -1 (-5500 5725)(-5950 5725);
WIRE 16 -1 (-5950 5725)(-5950 5850);
WIRE 16 -1 (-5500 5725)(-5500 5850);
WIRE 16 -1 (-5500 5650)(-5500 5725);
WIRE 16 3135 (-8475 6700)(-4725 6700);
WIRE 16 3135 (-8475 5450)(-8475 6700);
WIRE 16 3135 (-4725 5450)(-4725 6700);
WIRE 16 3135 (-8475 5450)(-4725 5450);
WIRE 16 3135 (-8450 5000)(-4525 5000);
WIRE 16 3135 (-8450 3725)(-8450 5000);
WIRE 16 3135 (-8450 3725)(-4525 3725);
WIRE 16 -1 (-8150 3975)(-8150 4100);
WIRE 16 -1 (-7700 3975)(-8150 3975);
WIRE 16 -1 (-7700 4100)(-7700 3975);
WIRE 16 -1 (-7250 3975)(-7700 3975);
WIRE 16 -1 (-7250 4100)(-7250 3975);
WIRE 16 -1 (-7250 3900)(-7250 3975);
WIRE 16 3135 (-4475 3725)(-4475 5000);
WIRE 16 -1 (-7250 4300)(-7250 4375);
WIRE 16 -1 (-7250 4375)(-7700 4375);
WIRE 16 -1 (-7700 4300)(-7700 4375);
WIRE 16 -1 (-7700 4375)(-8150 4375);
WIRE 16 -1 (-8150 4375)(-8150 4425);
WIRE 16 -1 (-8150 4375)(-8150 4300);
DOT 1 (-12700 4050);
DOT 1 (-9525 2125);
DOT 1 (-10875 4825);
DOT 1 (-13100 4450);
DOT 1 (-12675 4825);
DOT 1 (-13125 5225);
DOT 1 (-13125 6025);
DOT 1 (-12675 5225);
DOT 1 (-12675 5625);
DOT 1 (-12675 6025);
DOT 1 (-12225 4825);
DOT 1 (-11325 4825);
DOT 1 (-12225 5225);
DOT 1 (-11775 5225);
DOT 1 (-12225 5625);
DOT 1 (-12225 6025);
DOT 1 (-11775 5625);
DOT 1 (-11775 6025);
DOT 1 (-11325 5225);
DOT 1 (-11325 5625);
DOT 1 (-11325 6025);
DOT 1 (-10425 4825);
DOT 1 (-10875 5225);
DOT 1 (-10875 5625);
DOT 1 (-10875 6025);
DOT 1 (-10425 5225);
DOT 1 (-10425 5625);
DOT 1 (-10425 6025);
DOT 1 (-9975 4825);
DOT 1 (-9525 4825);
DOT 1 (-9975 5225);
DOT 1 (-9975 5625);
DOT 1 (-9975 6025);
DOT 1 (-9525 5225);
DOT 1 (-9525 5625);
DOT 1 (-9525 6025);
DOT 1 (-9125 4825);
DOT 1 (-9125 5625);
DOT 1 (-13125 1775);
DOT 1 (-12675 1375);
DOT 1 (-12675 1775);
DOT 1 (-13125 2525);
DOT 1 (-12675 2125);
DOT 1 (-12675 2525);
DOT 1 (-12225 1375);
DOT 1 (-12225 1775);
DOT 1 (-11775 1775);
DOT 1 (-11775 1375);
DOT 1 (-11325 1375);
DOT 1 (-11325 1775);
DOT 1 (-10875 1375);
DOT 1 (-12225 2125);
DOT 1 (-12225 2525);
DOT 1 (-11775 2125);
DOT 1 (-11775 2525);
DOT 1 (-11325 2125);
DOT 1 (-11325 2525);
DOT 1 (-10875 2125);
DOT 1 (-10425 2125);
DOT 1 (-9975 2125);
DOT 1 (-9525 2525);
DOT 1 (-9125 2125);
DOT 1 (-9975 2525);
DOT 1 (-10425 2525);
DOT 1 (-10875 2525);
DOT 1 (-7700 3975);
DOT 1 (-7250 3975);
DOT 1 (-8150 4375);
DOT 1 (-7700 4375);
DOT 1 (-8200 6125);
DOT 1 (-7750 5725);
DOT 1 (-7750 6125);
DOT 1 (-7300 5725);
DOT 1 (-7300 6125);
DOT 1 (-6850 5725);
DOT 1 (-6850 6125);
DOT 1 (-6400 5725);
DOT 1 (-6400 6125);
DOT 1 (-5950 5725);
DOT 1 (-5950 6125);
DOT 1 (-5500 5725);
DOT 1 (-11775 4825);
FORCENOTE
PVDD11_S3_P0: 16PCS 22UF ON TOP
(-13150 2850) 0;
DISPLAY LEFT (-13150 2850);
DISPLAY 2.510638 (-13150 2850);
PAINT WHITE (-13150 2850);
FORCENOTE
PVDD18_S5_P0: 3PCS 22UF ON TOP
(-8225 4675) 0;
DISPLAY LEFT (-8225 4675);
DISPLAY 2.510638 (-8225 4675);
PAINT WHITE (-8225 4675);
FORCENOTE
PVDDIO_P0: 7PCS 22UF ON TOP
(-8225 6450) 0;
DISPLAY LEFT (-8225 6450);
DISPLAY 2.510638 (-8225 6450);
PAINT WHITE (-8225 6450);
FORCENOTE
PVDDCR_SOC_P0: 22PCS 22UF ON TOP
(-13150 6400) 0;
DISPLAY LEFT (-13150 6400);
DISPLAY 2.510638 (-13150 6400);
PAINT WHITE (-13150 6400);
FORCENOTE
5
(-11350 5325) 0;
DISPLAY LEFT (-11350 5325);
DISPLAY 1.021277 (-11350 5325);
PAINT SKYBLUE (-11350 5325);
FORCENOTE
5
(-11350 6125) 0;
DISPLAY LEFT (-11350 6125);
DISPLAY 1.021277 (-11350 6125);
PAINT SKYBLUE (-11350 6125);
FORCENOTE
10
(-9175 5325) 0;
DISPLAY LEFT (-9175 5325);
DISPLAY 1.021277 (-9175 5325);
PAINT SKYBLUE (-9175 5325);
FORCENOTE
10
(-9175 6125) 0;
DISPLAY LEFT (-9175 6125);
DISPLAY 1.021277 (-9175 6125);
PAINT SKYBLUE (-9175 6125);
FORCENOTE
5
(-11350 1875) 0;
DISPLAY LEFT (-11350 1875);
DISPLAY 1.021277 (-11350 1875);
PAINT SKYBLUE (-11350 1875);
FORCENOTE
5
(-11350 2625) 0;
DISPLAY LEFT (-11350 2625);
DISPLAY 1.021277 (-11350 2625);
PAINT SKYBLUE (-11350 2625);
FORCENOTE
10
(-9175 2625) 0;
DISPLAY LEFT (-9175 2625);
DISPLAY 1.021277 (-9175 2625);
PAINT SKYBLUE (-9175 2625);
FORCENOTE
5
(-6425 6225) 0;
DISPLAY LEFT (-6425 6225);
DISPLAY 1.021277 (-6425 6225);
PAINT SKYBLUE (-6425 6225);
QUIT
